FILE_TYPE = MACRO_DRAWING;
SET COLOR_WIRE YELLOW;
SET COLOR_PROP ORANGE;
SET COLOR_DOT WHITE;
SET COLOR_ARC YELLOW;
SET COLOR_BODY GREEN;
SET COLOR_NOTE PURPLE;
SET PROP_DISPLAY VALUE;
SET PAGE_NUMBER P41;
SET PATH_NUMBER P126;
FORCEADD Q_CAP..1
(-4025 5850);
FORCEPROP 1 LAST VOLTAGE 25V
J 0
(-3975 5850);
DISPLAY 0.978723 (-3975 5850);
FORCEPROP 1 LAST TOLERANCE 10%
J 0
(-3975 5800);
DISPLAY 0.978723 (-3975 5800);
FORCEPROP 1 LAST PART_NUMBER CH4104K1B00
J 0
(-3975 5700);
DISPLAY 0.978723 (-3975 5700);
FORCEPROP 1 LAST MATERIAL X7R
J 0
(-3975 5750);
DISPLAY 0.978723 (-3975 5750);
FORCEPROP 1 LAST VALUE 0.1UF
J 0
(-3975 5900);
DISPLAY 0.978723 (-3975 5900);
FORCEPROP 1 LAST PACK_TYPE 0402
J 0
(-3975 5650);
DISPLAY 0.978723 (-3975 5650);
FORCEPROP 2 LAST CDS_LIB pure_quanta
J 0
(-4025 5850);
DISPLAY INVISIBLE (-4025 5850);
FORCEPROP 1 LAST PATH I1
J 0
(-3975 6000);
DISPLAY 0.978723 (-3975 6000);
PAINT WHITE (-3975 6000);
DISPLAY INVISIBLE (-3975 6000);
FORCEPROP 1 LAST $LOCATION C242
J 0
(-3975 5950);
DISPLAY 0.978723 (-3975 5950);
FORCEPROP 1 LASTPIN (-4025 5950) $PN 1
J 0
(-4015 5930);
DISPLAY 0.787234 (-4015 5930);
PAINT MONO (-4015 5930);
FORCEPROP 1 LASTPIN (-4025 5750) $PN 2
J 0
(-4015 5730);
DISPLAY 0.787234 (-4015 5730);
PAINT MONO (-4015 5730);
FORCEPROP 0 LAST CDS_LOCATION C242
J 0
(-3975 6000);
DISPLAY 0.680851 (-3975 6000);
DISPLAY INVISIBLE (-3975 6000);
FORCEPROP 0 LAST $SEC 1
J 0
(-3975 6000);
DISPLAY 0.680851 (-3975 6000);
PAINT MONO (-3975 6000);
DISPLAY INVISIBLE (-3975 6000);
FORCEPROP 0 LAST CDS_SEC 1
J 0
(-3975 6000);
DISPLAY 0.680851 (-3975 6000);
DISPLAY INVISIBLE (-3975 6000);
FORCEADD UNIVERSAL_GND..1
(-7900 5425);
FORCEPROP 3 LASTPIN (-7900 5475) SIG_NAME GND\g
J 0
(-7890 5485);
DISPLAY 0.659574 (-7890 5485);
PAINT MONO (-7890 5485);
DISPLAY INVISIBLE (-7890 5485);
FORCEPROP 2 LAST CDS_LIB logical_power
J 0
(-7900 5425);
PAINT MONO (-7900 5425);
DISPLAY INVISIBLE (-7900 5425);
FORCEPROP 2 LAST ROOM IO_SLOT
J 1
(-8125 5500);
DISPLAY 0.744681 (-8125 5500);
DISPLAY INVISIBLE (-8125 5500);
FORCEPROP 1 LAST HDL_POWER GND
J 1
(-7875 5350);
DISPLAY 0.702128 (-7875 5350);
PAINT GREEN (-7875 5350);
DISPLAY INVISIBLE (-7875 5350);
FORCEPROP 1 LAST PATH I100
J 0
(-7825 5425);
DISPLAY 0.872340 (-7825 5425);
PAINT AQUA (-7825 5425);
DISPLAY INVISIBLE (-7825 5425);
FORCEADD Q_CAP..1
(-7900 5700);
FORCEPROP 1 LAST PACK_TYPE C0603
J 0
(-7850 5500);
DISPLAY 0.978723 (-7850 5500);
FORCEPROP 1 LAST PART_NUMBER CH6103ME902
J 0
(-7850 5550);
DISPLAY 0.978723 (-7850 5550);
FORCEPROP 1 LAST VOLTAGE 16V
J 0
(-7850 5700);
DISPLAY 0.978723 (-7850 5700);
FORCEPROP 1 LAST VALUE 10UF
J 0
(-7850 5750);
DISPLAY 0.978723 (-7850 5750);
FORCEPROP 1 LAST MATERIAL X6S
J 0
(-7850 5600);
DISPLAY 0.978723 (-7850 5600);
FORCEPROP 1 LAST TOLERANCE 20%
J 0
(-7850 5650);
DISPLAY 0.978723 (-7850 5650);
FORCEPROP 1 LAST PATH I101
J 0
(-7850 5850);
DISPLAY 0.978723 (-7850 5850);
PAINT WHITE (-7850 5850);
DISPLAY INVISIBLE (-7850 5850);
FORCEPROP 2 LAST CDS_LIB pure_quanta
J 0
(-7900 5700);
DISPLAY INVISIBLE (-7900 5700);
FORCEPROP 1 LAST $LOCATION C194
J 0
(-7850 5800);
DISPLAY 0.978723 (-7850 5800);
FORCEPROP 1 LASTPIN (-7900 5800) $PN 1
J 0
(-7890 5780);
DISPLAY 0.787234 (-7890 5780);
PAINT MONO (-7890 5780);
FORCEPROP 1 LASTPIN (-7900 5600) $PN 2
J 0
(-7890 5580);
DISPLAY 0.787234 (-7890 5580);
PAINT MONO (-7890 5580);
FORCEPROP 0 LAST CDS_LOCATION C194
J 0
(-7850 5850);
DISPLAY 0.680851 (-7850 5850);
DISPLAY INVISIBLE (-7850 5850);
FORCEPROP 0 LAST $SEC 1
J 0
(-7850 5850);
DISPLAY 0.680851 (-7850 5850);
PAINT MONO (-7850 5850);
DISPLAY INVISIBLE (-7850 5850);
FORCEPROP 0 LAST CDS_SEC 1
J 0
(-7850 5850);
DISPLAY 0.680851 (-7850 5850);
DISPLAY INVISIBLE (-7850 5850);
FORCEADD UNIVERSAL_POWER..1
(-6025 2500);
FORCEPROP 3 LASTPIN (-6025 2450) SIG_NAME P3V3_AUX\g
J 0
(-6015 2460);
DISPLAY 0.659574 (-6015 2460);
PAINT MONO (-6015 2460);
DISPLAY INVISIBLE (-6015 2460);
FORCEPROP 1 LAST HDL_POWER P3V3_AUX
J 1
(-6025 2550);
DISPLAY 0.702128 (-6025 2550);
PAINT GREEN (-6025 2550);
FORCEPROP 1 LAST PATH I104
J 0
(-5975 2525);
DISPLAY 0.872340 (-5975 2525);
PAINT AQUA (-5975 2525);
DISPLAY INVISIBLE (-5975 2525);
FORCEPROP 2 LAST CDS_LIB logical_power
J 0
(-6025 2500);
PAINT MONO (-6025 2500);
DISPLAY INVISIBLE (-6025 2500);
FORCEADD Q_INDUCTOR..1
(-5550 2200);
FORCEPROP 2 LAST VALUE BLM18EG121SN1D/2A
J 0
(-5675 2075);
DISPLAY 0.510638 (-5675 2075);
PAINT SKYBLUE (-5675 2075);
FORCEPROP 1 LAST PART_NUMBER CX8EG121000
J 0
(-5675 2310);
DISPLAY 0.510638 (-5675 2310);
PAINT WHITE (-5675 2310);
FORCEPROP 2 LAST PACK_TYPE SMLF
J 0
(-5675 2125);
DISPLAY 0.510638 (-5675 2125);
PAINT SKYBLUE (-5675 2125);
FORCEPROP 1 LAST MATERIAL IND
J 0
(-5675 2255);
DISPLAY 0.510638 (-5675 2255);
PAINT SKYBLUE (-5675 2255);
FORCEPROP 1 LAST PATH I107
J 0
(-5475 2255);
DISPLAY 0.723404 (-5475 2255);
PAINT GREEN (-5475 2255);
DISPLAY INVISIBLE (-5475 2255);
FORCEPROP 2 LAST CDS_LIB pure_quanta
J 0
(-5550 2200);
DISPLAY INVISIBLE (-5550 2200);
FORCEPROP 1 LAST NEEDS_NO_SIZE TRUE
J 0
(-5550 2200);
DISPLAY 0.468085 (-5550 2200);
PAINT GREEN (-5550 2200);
DISPLAY INVISIBLE (-5550 2200);
FORCEPROP 1 LAST $LOCATION L19
J 0
(-5675 2360);
DISPLAY 0.702128 (-5675 2360);
PAINT YELLOW (-5675 2360);
FORCEPROP 0 LASTPIN (-5650 2175) $PN 1
J 2
(-5660 2185);
DISPLAY 0.808511 (-5660 2185);
PAINT WHITE (-5660 2185);
FORCEPROP 0 LASTPIN (-5450 2175) $PN 2
J 0
(-5440 2185);
DISPLAY 0.808511 (-5440 2185);
PAINT WHITE (-5440 2185);
FORCEPROP 0 LAST CDS_LOCATION L19
J 0
(-5675 2400);
DISPLAY 0.680851 (-5675 2400);
DISPLAY INVISIBLE (-5675 2400);
FORCEPROP 0 LAST $SEC 1
J 0
(-5675 2400);
DISPLAY 0.680851 (-5675 2400);
PAINT MONO (-5675 2400);
DISPLAY INVISIBLE (-5675 2400);
FORCEPROP 2 LAST CDS_SEC 1
J 0
(-5675 2350);
DISPLAY 1.021277 (-5675 2350);
DISPLAY INVISIBLE (-5675 2350);
FORCEADD Q_CAP..1
(-4650 1975);
FORCEPROP 1 LAST PACK_TYPE C0402
J 0
(-4600 1775);
DISPLAY 0.978723 (-4600 1775);
FORCEPROP 1 LAST TOLERANCE 10%
J 0
(-4600 1925);
DISPLAY 0.978723 (-4600 1925);
FORCEPROP 1 LAST VOLTAGE 25V
J 0
(-4600 1975);
DISPLAY 0.978723 (-4600 1975);
FORCEPROP 1 LAST PART_NUMBER CH5104KEB02
J 0
(-4600 1825);
DISPLAY 0.978723 (-4600 1825);
FORCEPROP 1 LAST MATERIAL X6S
J 0
(-4600 1875);
DISPLAY 0.978723 (-4600 1875);
FORCEPROP 1 LAST VALUE 1UF
J 0
(-4600 2025);
DISPLAY 0.978723 (-4600 2025);
FORCEPROP 1 LAST PATH I108
J 0
(-4600 2125);
DISPLAY 0.978723 (-4600 2125);
PAINT WHITE (-4600 2125);
DISPLAY INVISIBLE (-4600 2125);
FORCEPROP 2 LAST SEC_TYPE C0402
J 0
(-4600 2175);
DISPLAY 0.680851 (-4600 2175);
DISPLAY INVISIBLE (-4600 2175);
FORCEPROP 2 LAST CDS_LIB pure_quanta
J 0
(-4650 1975);
DISPLAY INVISIBLE (-4650 1975);
FORCEPROP 1 LAST $LOCATION C176
J 0
(-4600 2075);
DISPLAY 0.978723 (-4600 2075);
FORCEPROP 1 LASTPIN (-4650 2075) $PN 1
J 0
(-4640 2055);
DISPLAY 0.787234 (-4640 2055);
PAINT MONO (-4640 2055);
FORCEPROP 1 LASTPIN (-4650 1875) $PN 2
J 0
(-4640 1855);
DISPLAY 0.787234 (-4640 1855);
PAINT MONO (-4640 1855);
FORCEPROP 0 LAST CDS_LOCATION C176
J 0
(-4600 2125);
DISPLAY 0.680851 (-4600 2125);
DISPLAY INVISIBLE (-4600 2125);
FORCEPROP 2 LAST SEC 1
J 0
(-4600 2175);
DISPLAY 0.680851 (-4600 2175);
PAINT MONO (-4600 2175);
DISPLAY INVISIBLE (-4600 2175);
FORCEADD Q_CAP..1
(-4075 1950);
FORCEPROP 1 LAST TOLERANCE 10%
J 0
(-4025 1900);
DISPLAY 0.978723 (-4025 1900);
FORCEPROP 1 LAST VOLTAGE 25V
J 0
(-4025 1950);
DISPLAY 0.978723 (-4025 1950);
FORCEPROP 1 LAST VALUE 0.1UF
J 0
(-4025 2000);
DISPLAY 0.978723 (-4025 2000);
FORCEPROP 1 LAST MATERIAL X7R
J 0
(-4025 1850);
DISPLAY 0.978723 (-4025 1850);
FORCEPROP 1 LAST PACK_TYPE 0402
J 0
(-4025 1750);
DISPLAY 0.978723 (-4025 1750);
FORCEPROP 1 LAST PART_NUMBER CH4104K1B00
J 0
(-4025 1800);
DISPLAY 0.978723 (-4025 1800);
FORCEPROP 1 LAST PATH I109
J 0
(-4025 2100);
DISPLAY 0.978723 (-4025 2100);
PAINT WHITE (-4025 2100);
DISPLAY INVISIBLE (-4025 2100);
FORCEPROP 2 LAST SEC_TYPE 0402
J 0
(-4025 2150);
DISPLAY 0.680851 (-4025 2150);
DISPLAY INVISIBLE (-4025 2150);
FORCEPROP 2 LAST CDS_LIB pure_quanta
J 0
(-4075 1950);
DISPLAY INVISIBLE (-4075 1950);
FORCEPROP 1 LAST $LOCATION C193
J 0
(-4025 2050);
DISPLAY 0.978723 (-4025 2050);
FORCEPROP 1 LASTPIN (-4075 2050) $PN 1
J 0
(-4065 2030);
DISPLAY 0.787234 (-4065 2030);
PAINT MONO (-4065 2030);
FORCEPROP 1 LASTPIN (-4075 1850) $PN 2
J 0
(-4065 1830);
DISPLAY 0.787234 (-4065 1830);
PAINT MONO (-4065 1830);
FORCEPROP 0 LAST CDS_LOCATION C193
J 0
(-4025 2100);
DISPLAY 0.680851 (-4025 2100);
DISPLAY INVISIBLE (-4025 2100);
FORCEPROP 2 LAST SEC 1
J 0
(-4025 2150);
DISPLAY 0.680851 (-4025 2150);
PAINT MONO (-4025 2150);
DISPLAY INVISIBLE (-4025 2150);
FORCEADD UNIVERSAL_POWER..1
(-5575 6425);
FORCEPROP 3 LASTPIN (-5575 6375) SIG_NAME P3V3_AUX\g
J 0
(-5565 6385);
DISPLAY 0.659574 (-5565 6385);
PAINT MONO (-5565 6385);
DISPLAY INVISIBLE (-5565 6385);
FORCEPROP 1 LAST HDL_POWER P3V3_AUX
J 1
(-5575 6475);
DISPLAY 0.702128 (-5575 6475);
PAINT GREEN (-5575 6475);
FORCEPROP 2 LAST CDS_LIB logical_power
J 0
(-5575 6425);
DISPLAY INVISIBLE (-5575 6425);
FORCEPROP 1 LAST PATH I11
J 0
(-5525 6450);
DISPLAY 0.872340 (-5525 6450);
PAINT AQUA (-5525 6450);
DISPLAY INVISIBLE (-5525 6450);
FORCEADD UNIVERSAL_GND..1
(-2600 1525);
FORCEPROP 3 LASTPIN (-2600 1575) SIG_NAME GND\g
J 0
(-2590 1585);
DISPLAY 0.659574 (-2590 1585);
PAINT MONO (-2590 1585);
DISPLAY INVISIBLE (-2590 1585);
FORCEPROP 1 LAST PATH I112
J 0
(-2525 1525);
DISPLAY 0.872340 (-2525 1525);
PAINT AQUA (-2525 1525);
DISPLAY INVISIBLE (-2525 1525);
FORCEPROP 1 LAST HDL_POWER GND
J 1
(-2575 1450);
DISPLAY 0.702128 (-2575 1450);
PAINT GREEN (-2575 1450);
DISPLAY INVISIBLE (-2575 1450);
FORCEPROP 2 LAST CDS_LIB logical_power
J 0
(-2600 1525);
PAINT MONO (-2600 1525);
DISPLAY INVISIBLE (-2600 1525);
FORCEPROP 2 LAST ROOM IO_SLOT
J 1
(-2825 1600);
DISPLAY 0.744681 (-2825 1600);
DISPLAY INVISIBLE (-2825 1600);
FORCEADD UNIVERSAL_POWER..1
(-250 2250);
FORCEPROP 3 LASTPIN (-250 2200) SIG_NAME PVCCA_AUX_PLD\g
J 0
(-240 2210);
DISPLAY 0.659574 (-240 2210);
PAINT MONO (-240 2210);
DISPLAY INVISIBLE (-240 2210);
FORCEPROP 1 LAST HDL_POWER PVCCA_AUX_PLD
J 1
(-250 2300);
DISPLAY 0.702128 (-250 2300);
PAINT GREEN (-250 2300);
FORCEPROP 1 LAST PATH I114
J 0
(-200 2275);
DISPLAY 0.872340 (-200 2275);
PAINT AQUA (-200 2275);
DISPLAY INVISIBLE (-200 2275);
FORCEPROP 2 LAST CDS_LIB logical_power
J 0
(-250 2250);
DISPLAY INVISIBLE (-250 2250);
FORCEADD Q_CAP..1
(-3450 1950);
FORCEPROP 1 LAST PART_NUMBER CH4104K1B00
J 0
(-3400 1800);
DISPLAY 0.978723 (-3400 1800);
FORCEPROP 1 LAST TOLERANCE 10%
J 0
(-3400 1900);
DISPLAY 0.978723 (-3400 1900);
FORCEPROP 1 LAST VOLTAGE 25V
J 0
(-3400 1950);
DISPLAY 0.978723 (-3400 1950);
FORCEPROP 1 LAST VALUE 0.1UF
J 0
(-3400 2000);
DISPLAY 0.978723 (-3400 2000);
FORCEPROP 1 LAST MATERIAL X7R
J 0
(-3400 1850);
DISPLAY 0.978723 (-3400 1850);
FORCEPROP 1 LAST PACK_TYPE 0402
J 0
(-3400 1750);
DISPLAY 0.978723 (-3400 1750);
FORCEPROP 2 LAST CDS_LIB pure_quanta
J 0
(-3450 1950);
DISPLAY INVISIBLE (-3450 1950);
FORCEPROP 1 LAST PATH I115
J 0
(-3400 2100);
DISPLAY 0.978723 (-3400 2100);
PAINT WHITE (-3400 2100);
DISPLAY INVISIBLE (-3400 2100);
FORCEPROP 1 LAST $LOCATION C250
J 0
(-3400 2050);
DISPLAY 0.978723 (-3400 2050);
FORCEPROP 1 LASTPIN (-3450 2050) $PN 1
J 0
(-3440 2030);
DISPLAY 0.787234 (-3440 2030);
PAINT MONO (-3440 2030);
FORCEPROP 1 LASTPIN (-3450 1850) $PN 2
J 0
(-3440 1830);
DISPLAY 0.787234 (-3440 1830);
PAINT MONO (-3440 1830);
FORCEPROP 0 LAST CDS_LOCATION C250
J 0
(-3400 2100);
DISPLAY 0.680851 (-3400 2100);
DISPLAY INVISIBLE (-3400 2100);
FORCEPROP 0 LAST $SEC 1
J 0
(-3400 2100);
DISPLAY 0.680851 (-3400 2100);
PAINT MONO (-3400 2100);
DISPLAY INVISIBLE (-3400 2100);
FORCEPROP 0 LAST CDS_SEC 1
J 0
(-3400 2100);
DISPLAY 0.680851 (-3400 2100);
DISPLAY INVISIBLE (-3400 2100);
FORCEADD Q_CAP..1
(-2875 1950);
FORCEPROP 1 LAST MATERIAL X7R
J 0
(-2825 1850);
DISPLAY 0.978723 (-2825 1850);
FORCEPROP 1 LAST TOLERANCE 10%
J 0
(-2825 1900);
DISPLAY 0.978723 (-2825 1900);
FORCEPROP 1 LAST VALUE 0.1UF
J 0
(-2825 2000);
DISPLAY 0.978723 (-2825 2000);
FORCEPROP 1 LAST VOLTAGE 25V
J 0
(-2825 1950);
DISPLAY 0.978723 (-2825 1950);
FORCEPROP 1 LAST PACK_TYPE 0402
J 0
(-2825 1750);
DISPLAY 0.978723 (-2825 1750);
FORCEPROP 1 LAST PART_NUMBER CH4104K1B00
J 0
(-2825 1800);
DISPLAY 0.978723 (-2825 1800);
FORCEPROP 1 LAST PATH I116
J 0
(-2825 2100);
DISPLAY 0.978723 (-2825 2100);
PAINT WHITE (-2825 2100);
DISPLAY INVISIBLE (-2825 2100);
FORCEPROP 2 LAST CDS_LIB pure_quanta
J 0
(-2875 1950);
DISPLAY INVISIBLE (-2875 1950);
FORCEPROP 1 LAST $LOCATION C190
J 0
(-2825 2050);
DISPLAY 0.978723 (-2825 2050);
FORCEPROP 1 LASTPIN (-2875 2050) $PN 1
J 0
(-2865 2030);
DISPLAY 0.787234 (-2865 2030);
PAINT MONO (-2865 2030);
FORCEPROP 1 LASTPIN (-2875 1850) $PN 2
J 0
(-2865 1830);
DISPLAY 0.787234 (-2865 1830);
PAINT MONO (-2865 1830);
FORCEPROP 0 LAST CDS_LOCATION C190
J 0
(-2825 2100);
DISPLAY 0.680851 (-2825 2100);
DISPLAY INVISIBLE (-2825 2100);
FORCEPROP 0 LAST $SEC 1
J 0
(-2825 2100);
DISPLAY 0.680851 (-2825 2100);
PAINT MONO (-2825 2100);
DISPLAY INVISIBLE (-2825 2100);
FORCEPROP 0 LAST CDS_SEC 1
J 0
(-2825 2100);
DISPLAY 0.680851 (-2825 2100);
DISPLAY INVISIBLE (-2825 2100);
FORCEADD Q_CAP..1
(-2325 1950);
FORCEPROP 1 LAST VOLTAGE 25V
J 0
(-2275 1950);
DISPLAY 0.978723 (-2275 1950);
FORCEPROP 1 LAST MATERIAL X7R
J 0
(-2275 1850);
DISPLAY 0.978723 (-2275 1850);
FORCEPROP 1 LAST TOLERANCE 10%
J 0
(-2275 1900);
DISPLAY 0.978723 (-2275 1900);
FORCEPROP 1 LAST PART_NUMBER CH4104K1B00
J 0
(-2275 1800);
DISPLAY 0.978723 (-2275 1800);
FORCEPROP 1 LAST PACK_TYPE 0402
J 0
(-2275 1750);
DISPLAY 0.978723 (-2275 1750);
FORCEPROP 1 LAST VALUE 0.1UF
J 0
(-2275 2000);
DISPLAY 0.978723 (-2275 2000);
FORCEPROP 2 LAST CDS_LIB pure_quanta
J 0
(-2325 1950);
DISPLAY INVISIBLE (-2325 1950);
FORCEPROP 1 LAST PATH I117
J 0
(-2275 2100);
DISPLAY 0.978723 (-2275 2100);
PAINT WHITE (-2275 2100);
DISPLAY INVISIBLE (-2275 2100);
FORCEPROP 1 LAST $LOCATION C263
J 0
(-2275 2050);
DISPLAY 0.978723 (-2275 2050);
FORCEPROP 1 LASTPIN (-2325 2050) $PN 1
J 0
(-2315 2030);
DISPLAY 0.787234 (-2315 2030);
PAINT MONO (-2315 2030);
FORCEPROP 1 LASTPIN (-2325 1850) $PN 2
J 0
(-2315 1830);
DISPLAY 0.787234 (-2315 1830);
PAINT MONO (-2315 1830);
FORCEPROP 0 LAST CDS_LOCATION C263
J 0
(-2275 2100);
DISPLAY 0.680851 (-2275 2100);
DISPLAY INVISIBLE (-2275 2100);
FORCEPROP 0 LAST $SEC 1
J 0
(-2275 2100);
DISPLAY 0.680851 (-2275 2100);
PAINT MONO (-2275 2100);
DISPLAY INVISIBLE (-2275 2100);
FORCEPROP 0 LAST CDS_SEC 1
J 0
(-2275 2100);
DISPLAY 0.680851 (-2275 2100);
DISPLAY INVISIBLE (-2275 2100);
FORCEADD Q_CAP..1
(-1200 1950);
FORCEPROP 1 LAST VOLTAGE 25V
J 0
(-1150 1950);
DISPLAY 0.978723 (-1150 1950);
FORCEPROP 1 LAST PART_NUMBER CH4104K1B00
J 0
(-1150 1800);
DISPLAY 0.978723 (-1150 1800);
FORCEPROP 1 LAST PACK_TYPE 0402
J 0
(-1150 1750);
DISPLAY 0.978723 (-1150 1750);
FORCEPROP 1 LAST MATERIAL X7R
J 0
(-1150 1850);
DISPLAY 0.978723 (-1150 1850);
FORCEPROP 1 LAST TOLERANCE 10%
J 0
(-1150 1900);
DISPLAY 0.978723 (-1150 1900);
FORCEPROP 1 LAST VALUE 0.1UF
J 0
(-1150 2000);
DISPLAY 0.978723 (-1150 2000);
FORCEPROP 2 LAST CDS_LIB pure_quanta
J 0
(-1200 1950);
DISPLAY INVISIBLE (-1200 1950);
FORCEPROP 1 LAST PATH I118
J 0
(-1150 2100);
DISPLAY 0.978723 (-1150 2100);
PAINT WHITE (-1150 2100);
DISPLAY INVISIBLE (-1150 2100);
FORCEPROP 1 LAST $LOCATION C269
J 0
(-1150 2050);
DISPLAY 0.978723 (-1150 2050);
FORCEPROP 1 LASTPIN (-1200 2050) $PN 1
J 0
(-1190 2030);
DISPLAY 0.787234 (-1190 2030);
PAINT MONO (-1190 2030);
FORCEPROP 1 LASTPIN (-1200 1850) $PN 2
J 0
(-1190 1830);
DISPLAY 0.787234 (-1190 1830);
PAINT MONO (-1190 1830);
FORCEPROP 0 LAST CDS_LOCATION C269
J 0
(-1150 2100);
DISPLAY 0.680851 (-1150 2100);
DISPLAY INVISIBLE (-1150 2100);
FORCEPROP 0 LAST $SEC 1
J 0
(-1150 2100);
DISPLAY 0.680851 (-1150 2100);
PAINT MONO (-1150 2100);
DISPLAY INVISIBLE (-1150 2100);
FORCEPROP 0 LAST CDS_SEC 1
J 0
(-1150 2100);
DISPLAY 0.680851 (-1150 2100);
DISPLAY INVISIBLE (-1150 2100);
FORCEADD Q_CAP..1
(-1775 1950);
FORCEPROP 1 LAST PACK_TYPE 0402
J 0
(-1725 1750);
DISPLAY 0.978723 (-1725 1750);
FORCEPROP 1 LAST PART_NUMBER CH4104K1B00
J 0
(-1725 1800);
DISPLAY 0.978723 (-1725 1800);
FORCEPROP 1 LAST VALUE 0.1UF
J 0
(-1725 2000);
DISPLAY 0.978723 (-1725 2000);
FORCEPROP 1 LAST VOLTAGE 25V
J 0
(-1725 1950);
DISPLAY 0.978723 (-1725 1950);
FORCEPROP 1 LAST TOLERANCE 10%
J 0
(-1725 1900);
DISPLAY 0.978723 (-1725 1900);
FORCEPROP 1 LAST MATERIAL X7R
J 0
(-1725 1850);
DISPLAY 0.978723 (-1725 1850);
FORCEPROP 2 LAST CDS_LIB pure_quanta
J 0
(-1775 1950);
DISPLAY INVISIBLE (-1775 1950);
FORCEPROP 1 LAST PATH I119
J 0
(-1725 2100);
DISPLAY 0.978723 (-1725 2100);
PAINT WHITE (-1725 2100);
DISPLAY INVISIBLE (-1725 2100);
FORCEPROP 1 LAST $LOCATION C266
J 0
(-1725 2050);
DISPLAY 0.978723 (-1725 2050);
FORCEPROP 1 LASTPIN (-1775 2050) $PN 1
J 0
(-1765 2030);
DISPLAY 0.787234 (-1765 2030);
PAINT MONO (-1765 2030);
FORCEPROP 1 LASTPIN (-1775 1850) $PN 2
J 0
(-1765 1830);
DISPLAY 0.787234 (-1765 1830);
PAINT MONO (-1765 1830);
FORCEPROP 0 LAST CDS_LOCATION C266
J 0
(-1725 2100);
DISPLAY 0.680851 (-1725 2100);
DISPLAY INVISIBLE (-1725 2100);
FORCEPROP 0 LAST $SEC 1
J 0
(-1725 2100);
DISPLAY 0.680851 (-1725 2100);
PAINT MONO (-1725 2100);
DISPLAY INVISIBLE (-1725 2100);
FORCEPROP 0 LAST CDS_SEC 1
J 0
(-1725 2100);
DISPLAY 0.680851 (-1725 2100);
DISPLAY INVISIBLE (-1725 2100);
FORCEADD Q_CAP..1
(-5225 1950);
FORCEPROP 1 LAST PACK_TYPE C0603
J 0
(-5175 1750);
DISPLAY 0.978723 (-5175 1750);
FORCEPROP 1 LAST PART_NUMBER CH6103ME902
J 0
(-5175 1800);
DISPLAY 0.978723 (-5175 1800);
FORCEPROP 1 LAST VOLTAGE 16V
J 0
(-5175 1950);
DISPLAY 0.978723 (-5175 1950);
FORCEPROP 1 LAST TOLERANCE 20%
J 0
(-5175 1900);
DISPLAY 0.978723 (-5175 1900);
FORCEPROP 1 LAST MATERIAL X6S
J 0
(-5175 1850);
DISPLAY 0.978723 (-5175 1850);
FORCEPROP 1 LAST VALUE 10UF
J 0
(-5175 2000);
DISPLAY 0.978723 (-5175 2000);
FORCEPROP 2 LAST CDS_LIB pure_quanta
J 0
(-5225 1950);
DISPLAY INVISIBLE (-5225 1950);
FORCEPROP 1 LAST PATH I122
J 0
(-5175 2100);
DISPLAY 0.978723 (-5175 2100);
PAINT WHITE (-5175 2100);
DISPLAY INVISIBLE (-5175 2100);
FORCEPROP 1 LAST $LOCATION C163
J 0
(-5175 2050);
DISPLAY 0.978723 (-5175 2050);
FORCEPROP 1 LASTPIN (-5225 2050) $PN 1
J 0
(-5215 2030);
DISPLAY 0.787234 (-5215 2030);
PAINT MONO (-5215 2030);
FORCEPROP 1 LASTPIN (-5225 1850) $PN 2
J 0
(-5215 1830);
DISPLAY 0.787234 (-5215 1830);
PAINT MONO (-5215 1830);
FORCEPROP 0 LAST CDS_LOCATION C163
J 0
(-5175 2100);
DISPLAY 0.680851 (-5175 2100);
DISPLAY INVISIBLE (-5175 2100);
FORCEPROP 0 LAST $SEC 1
J 0
(-5175 2100);
DISPLAY 0.680851 (-5175 2100);
PAINT MONO (-5175 2100);
DISPLAY INVISIBLE (-5175 2100);
FORCEPROP 0 LAST CDS_SEC 1
J 0
(-5175 2100);
DISPLAY 0.680851 (-5175 2100);
DISPLAY INVISIBLE (-5175 2100);
FORCEADD Q_CAP..1
(-575 1950);
FORCEPROP 1 LAST VOLTAGE 50V
J 0
(-525 1950);
DISPLAY 0.978723 (-525 1950);
FORCEPROP 1 LAST TOLERANCE 10%
J 0
(-525 1900);
DISPLAY 0.978723 (-525 1900);
FORCEPROP 1 LAST PACK_TYPE C0402
J 0
(-525 1750);
DISPLAY 0.978723 (-525 1750);
FORCEPROP 1 LAST PART_NUMBER CH31006KB18
J 0
(-525 1800);
DISPLAY 0.978723 (-525 1800);
FORCEPROP 1 LAST VALUE 0.01UF
J 0
(-525 2000);
DISPLAY 0.978723 (-525 2000);
FORCEPROP 1 LAST MATERIAL EMPTY
J 0
(-525 1850);
DISPLAY 0.978723 (-525 1850);
PAINT RED (-525 1850);
FORCEPROP 1 LAST PATH I123
J 0
(-525 2100);
DISPLAY 0.978723 (-525 2100);
PAINT WHITE (-525 2100);
DISPLAY INVISIBLE (-525 2100);
FORCEPROP 2 LAST CDS_LIB pure_quanta
J 0
(-575 1950);
DISPLAY INVISIBLE (-575 1950);
FORCEPROP 1 LAST $LOCATION C286
J 0
(-525 2050);
DISPLAY 0.978723 (-525 2050);
FORCEPROP 1 LASTPIN (-575 2050) $PN 1
J 0
(-565 2030);
DISPLAY 0.787234 (-565 2030);
PAINT MONO (-565 2030);
FORCEPROP 1 LASTPIN (-575 1850) $PN 2
J 0
(-565 1830);
DISPLAY 0.787234 (-565 1830);
PAINT MONO (-565 1830);
FORCEPROP 0 LAST CDS_LOCATION C286
J 0
(-525 2100);
DISPLAY 0.680851 (-525 2100);
DISPLAY INVISIBLE (-525 2100);
FORCEPROP 0 LAST $SEC 1
J 0
(-525 2100);
DISPLAY 0.680851 (-525 2100);
PAINT MONO (-525 2100);
DISPLAY INVISIBLE (-525 2100);
FORCEPROP 0 LAST CDS_SEC 1
J 0
(-525 2100);
DISPLAY 0.680851 (-525 2100);
DISPLAY INVISIBLE (-525 2100);
FORCEADD Q_CAP..1
(-1550 3575);
FORCEPROP 1 LAST VOLTAGE 50V
J 0
(-1500 3575);
DISPLAY 0.978723 (-1500 3575);
FORCEPROP 1 LAST TOLERANCE 10%
J 0
(-1500 3525);
DISPLAY 0.978723 (-1500 3525);
FORCEPROP 1 LAST VALUE 0.01UF
J 0
(-1500 3625);
DISPLAY 0.978723 (-1500 3625);
FORCEPROP 1 LAST PACK_TYPE C0402
J 0
(-1500 3375);
DISPLAY 0.978723 (-1500 3375);
FORCEPROP 1 LAST PART_NUMBER CH31006KB18
J 0
(-1500 3425);
DISPLAY 0.978723 (-1500 3425);
FORCEPROP 1 LAST MATERIAL EMPTY
J 0
(-1500 3475);
DISPLAY 0.978723 (-1500 3475);
PAINT RED (-1500 3475);
FORCEPROP 1 LAST PATH I124
J 0
(-1500 3725);
DISPLAY 0.978723 (-1500 3725);
PAINT WHITE (-1500 3725);
DISPLAY INVISIBLE (-1500 3725);
FORCEPROP 2 LAST CDS_LIB pure_quanta
J 0
(-1550 3575);
DISPLAY INVISIBLE (-1550 3575);
FORCEPROP 1 LAST $LOCATION C285
J 0
(-1500 3675);
DISPLAY 0.978723 (-1500 3675);
FORCEPROP 1 LASTPIN (-1550 3675) $PN 1
J 0
(-1540 3655);
DISPLAY 0.787234 (-1540 3655);
PAINT MONO (-1540 3655);
FORCEPROP 1 LASTPIN (-1550 3475) $PN 2
J 0
(-1540 3455);
DISPLAY 0.787234 (-1540 3455);
PAINT MONO (-1540 3455);
FORCEPROP 0 LAST CDS_LOCATION C285
J 0
(-1500 3725);
DISPLAY 0.680851 (-1500 3725);
DISPLAY INVISIBLE (-1500 3725);
FORCEPROP 0 LAST $SEC 1
J 0
(-1500 3725);
DISPLAY 0.680851 (-1500 3725);
PAINT MONO (-1500 3725);
DISPLAY INVISIBLE (-1500 3725);
FORCEPROP 0 LAST CDS_SEC 1
J 0
(-1500 3725);
DISPLAY 0.680851 (-1500 3725);
DISPLAY INVISIBLE (-1500 3725);
FORCEADD Q_CAP..1
(-1575 4675);
FORCEPROP 1 LAST VOLTAGE 50V
J 0
(-1525 4675);
DISPLAY 0.978723 (-1525 4675);
FORCEPROP 1 LAST PACK_TYPE C0402
J 0
(-1525 4475);
DISPLAY 0.978723 (-1525 4475);
FORCEPROP 1 LAST PART_NUMBER CH31006KB18
J 0
(-1525 4525);
DISPLAY 0.978723 (-1525 4525);
FORCEPROP 1 LAST TOLERANCE 10%
J 0
(-1525 4625);
DISPLAY 0.978723 (-1525 4625);
FORCEPROP 1 LAST VALUE 0.01UF
J 0
(-1525 4725);
DISPLAY 0.978723 (-1525 4725);
FORCEPROP 1 LAST MATERIAL EMPTY
J 0
(-1525 4575);
DISPLAY 0.978723 (-1525 4575);
PAINT RED (-1525 4575);
FORCEPROP 1 LAST PATH I125
J 0
(-1525 4825);
DISPLAY 0.978723 (-1525 4825);
PAINT WHITE (-1525 4825);
DISPLAY INVISIBLE (-1525 4825);
FORCEPROP 2 LAST CDS_LIB pure_quanta
J 0
(-1575 4675);
DISPLAY INVISIBLE (-1575 4675);
FORCEPROP 1 LAST $LOCATION C281
J 0
(-1525 4775);
DISPLAY 0.978723 (-1525 4775);
FORCEPROP 1 LASTPIN (-1575 4775) $PN 1
J 0
(-1565 4755);
DISPLAY 0.787234 (-1565 4755);
PAINT MONO (-1565 4755);
FORCEPROP 1 LASTPIN (-1575 4575) $PN 2
J 0
(-1565 4555);
DISPLAY 0.787234 (-1565 4555);
PAINT MONO (-1565 4555);
FORCEPROP 0 LAST CDS_LOCATION C281
J 0
(-1525 4825);
DISPLAY 0.680851 (-1525 4825);
DISPLAY INVISIBLE (-1525 4825);
FORCEPROP 0 LAST $SEC 1
J 0
(-1525 4825);
DISPLAY 0.680851 (-1525 4825);
PAINT MONO (-1525 4825);
DISPLAY INVISIBLE (-1525 4825);
FORCEPROP 0 LAST CDS_SEC 1
J 0
(-1525 4825);
DISPLAY 0.680851 (-1525 4825);
DISPLAY INVISIBLE (-1525 4825);
FORCEADD Q_CAP..1
(-1550 5850);
FORCEPROP 1 LAST VOLTAGE 50V
J 0
(-1500 5850);
DISPLAY 0.978723 (-1500 5850);
FORCEPROP 1 LAST TOLERANCE 10%
J 0
(-1500 5800);
DISPLAY 0.978723 (-1500 5800);
FORCEPROP 1 LAST VALUE 0.01UF
J 0
(-1500 5900);
DISPLAY 0.978723 (-1500 5900);
FORCEPROP 1 LAST PACK_TYPE C0402
J 0
(-1500 5650);
DISPLAY 0.978723 (-1500 5650);
FORCEPROP 1 LAST PART_NUMBER CH31006KB18
J 0
(-1500 5700);
DISPLAY 0.978723 (-1500 5700);
FORCEPROP 1 LAST MATERIAL EMPTY
J 0
(-1500 5750);
DISPLAY 0.978723 (-1500 5750);
PAINT RED (-1500 5750);
FORCEPROP 1 LAST PATH I126
J 0
(-1500 6000);
DISPLAY 0.978723 (-1500 6000);
PAINT WHITE (-1500 6000);
DISPLAY INVISIBLE (-1500 6000);
FORCEPROP 2 LAST CDS_LIB pure_quanta
J 0
(-1550 5850);
DISPLAY INVISIBLE (-1550 5850);
FORCEPROP 1 LAST $LOCATION C283
J 0
(-1500 5950);
DISPLAY 0.978723 (-1500 5950);
FORCEPROP 1 LASTPIN (-1550 5950) $PN 1
J 0
(-1540 5930);
DISPLAY 0.787234 (-1540 5930);
PAINT MONO (-1540 5930);
FORCEPROP 1 LASTPIN (-1550 5750) $PN 2
J 0
(-1540 5730);
DISPLAY 0.787234 (-1540 5730);
PAINT MONO (-1540 5730);
FORCEPROP 0 LAST CDS_LOCATION C283
J 0
(-1500 6000);
DISPLAY 0.680851 (-1500 6000);
DISPLAY INVISIBLE (-1500 6000);
FORCEPROP 0 LAST $SEC 1
J 0
(-1500 6000);
DISPLAY 0.680851 (-1500 6000);
PAINT MONO (-1500 6000);
DISPLAY INVISIBLE (-1500 6000);
FORCEPROP 0 LAST CDS_SEC 1
J 0
(-1500 6000);
DISPLAY 0.680851 (-1500 6000);
DISPLAY INVISIBLE (-1500 6000);
FORCEADD UNIVERSAL_POWER..1
(-5575 5225);
FORCEPROP 3 LASTPIN (-5575 5175) SIG_NAME P3V3_AUX\g
J 0
(-5565 5185);
DISPLAY 0.659574 (-5565 5185);
PAINT MONO (-5565 5185);
DISPLAY INVISIBLE (-5565 5185);
FORCEPROP 1 LAST HDL_POWER P3V3_AUX
J 1
(-5575 5275);
DISPLAY 0.702128 (-5575 5275);
PAINT GREEN (-5575 5275);
FORCEPROP 1 LAST PATH I18
J 0
(-5525 5250);
DISPLAY 0.872340 (-5525 5250);
PAINT AQUA (-5525 5250);
DISPLAY INVISIBLE (-5525 5250);
FORCEPROP 2 LAST CDS_LIB logical_power
J 0
(-5575 5225);
DISPLAY INVISIBLE (-5575 5225);
FORCEADD UNIVERSAL_GND..1
(-2625 4275);
FORCEPROP 3 LASTPIN (-2625 4325) SIG_NAME GND\g
J 0
(-2615 4335);
DISPLAY 0.659574 (-2615 4335);
PAINT MONO (-2615 4335);
DISPLAY INVISIBLE (-2615 4335);
FORCEPROP 2 LAST CDS_LIB logical_power
J 0
(-2625 4275);
DISPLAY INVISIBLE (-2625 4275);
FORCEPROP 1 LAST PATH I24
J 0
(-2550 4275);
DISPLAY 0.872340 (-2550 4275);
PAINT AQUA (-2550 4275);
DISPLAY INVISIBLE (-2550 4275);
FORCEPROP 2 LAST ROOM IO_SLOT
J 1
(-2850 4350);
DISPLAY 0.744681 (-2850 4350);
DISPLAY INVISIBLE (-2850 4350);
FORCEPROP 1 LAST HDL_POWER GND
J 1
(-2600 4200);
DISPLAY 0.702128 (-2600 4200);
PAINT GREEN (-2600 4200);
DISPLAY INVISIBLE (-2600 4200);
FORCEADD UNIVERSAL_POWER..1
(-425 5025);
FORCEPROP 3 LASTPIN (-425 4975) SIG_NAME VCCIO1\g
J 0
(-415 4985);
DISPLAY 0.659574 (-415 4985);
PAINT MONO (-415 4985);
DISPLAY INVISIBLE (-415 4985);
FORCEPROP 1 LAST HDL_POWER VCCIO1
J 1
(-425 5075);
DISPLAY 0.702128 (-425 5075);
PAINT GREEN (-425 5075);
FORCEPROP 1 LAST PATH I26
J 0
(-375 5050);
DISPLAY 0.872340 (-375 5050);
PAINT AQUA (-375 5050);
DISPLAY INVISIBLE (-375 5050);
FORCEPROP 2 LAST CDS_LIB logical_power
J 0
(-425 5025);
DISPLAY INVISIBLE (-425 5025);
FORCEADD UNIVERSAL_POWER..1
(-750 3925);
FORCEPROP 3 LASTPIN (-750 3875) SIG_NAME VCCIO2\g
J 0
(-740 3885);
DISPLAY 0.659574 (-740 3885);
PAINT MONO (-740 3885);
DISPLAY INVISIBLE (-740 3885);
FORCEPROP 1 LAST HDL_POWER VCCIO2
J 1
(-750 3975);
DISPLAY 0.702128 (-750 3975);
PAINT GREEN (-750 3975);
FORCEPROP 1 LAST PATH I27
J 0
(-700 3950);
DISPLAY 0.872340 (-700 3950);
PAINT AQUA (-700 3950);
DISPLAY INVISIBLE (-700 3950);
FORCEPROP 2 LAST CDS_LIB logical_power
J 0
(-750 3925);
DISPLAY INVISIBLE (-750 3925);
FORCEADD UNIVERSAL_GND..1
(-2625 3175);
FORCEPROP 3 LASTPIN (-2625 3225) SIG_NAME GND\g
J 0
(-2615 3235);
DISPLAY 0.659574 (-2615 3235);
PAINT MONO (-2615 3235);
DISPLAY INVISIBLE (-2615 3235);
FORCEPROP 2 LAST CDS_LIB logical_power
J 0
(-2625 3175);
DISPLAY INVISIBLE (-2625 3175);
FORCEPROP 1 LAST PATH I29
J 0
(-2550 3175);
DISPLAY 0.872340 (-2550 3175);
PAINT AQUA (-2550 3175);
DISPLAY INVISIBLE (-2550 3175);
FORCEPROP 1 LAST HDL_POWER GND
J 1
(-2600 3100);
DISPLAY 0.702128 (-2600 3100);
PAINT GREEN (-2600 3100);
DISPLAY INVISIBLE (-2600 3100);
FORCEPROP 2 LAST ROOM IO_SLOT
J 1
(-2850 3250);
DISPLAY 0.744681 (-2850 3250);
DISPLAY INVISIBLE (-2850 3250);
FORCEADD UNIVERSAL_POWER..1
(-5575 4125);
FORCEPROP 3 LASTPIN (-5575 4075) SIG_NAME P3V3_AUX\g
J 0
(-5565 4085);
DISPLAY 0.659574 (-5565 4085);
PAINT MONO (-5565 4085);
DISPLAY INVISIBLE (-5565 4085);
FORCEPROP 1 LAST HDL_POWER P3V3_AUX
J 1
(-5575 4175);
DISPLAY 0.702128 (-5575 4175);
PAINT GREEN (-5575 4175);
FORCEPROP 1 LAST PATH I35
J 0
(-5525 4150);
DISPLAY 0.872340 (-5525 4150);
PAINT AQUA (-5525 4150);
DISPLAY INVISIBLE (-5525 4150);
FORCEPROP 2 LAST CDS_LIB logical_power
J 0
(-5575 4125);
DISPLAY INVISIBLE (-5575 4125);
FORCEADD UNIVERSAL_POWER..1
(-6825 3575);
FORCEPROP 3 LASTPIN (-6825 3525) SIG_NAME VCCIO3\g
J 0
(-6815 3535);
DISPLAY 0.659574 (-6815 3535);
PAINT MONO (-6815 3535);
DISPLAY INVISIBLE (-6815 3535);
FORCEPROP 1 LAST HDL_POWER VCCIO3
J 1
(-6825 3625);
DISPLAY 0.702128 (-6825 3625);
PAINT GREEN (-6825 3625);
FORCEPROP 1 LAST PATH I40
J 0
(-6775 3600);
DISPLAY 0.872340 (-6775 3600);
PAINT AQUA (-6775 3600);
DISPLAY INVISIBLE (-6775 3600);
FORCEPROP 2 LAST CDS_LIB logical_power
J 0
(-6825 3575);
DISPLAY INVISIBLE (-6825 3575);
FORCEADD UNIVERSAL_GND..1
(-7200 2825);
FORCEPROP 3 LASTPIN (-7200 2875) SIG_NAME GND\g
J 0
(-7190 2885);
DISPLAY 0.659574 (-7190 2885);
PAINT MONO (-7190 2885);
DISPLAY INVISIBLE (-7190 2885);
FORCEPROP 1 LAST HDL_POWER GND
J 1
(-7175 2750);
DISPLAY 0.702128 (-7175 2750);
PAINT GREEN (-7175 2750);
DISPLAY INVISIBLE (-7175 2750);
FORCEPROP 2 LAST ROOM IO_SLOT
J 1
(-7425 2900);
DISPLAY 0.744681 (-7425 2900);
DISPLAY INVISIBLE (-7425 2900);
FORCEPROP 1 LAST PATH I42
J 0
(-7125 2825);
DISPLAY 0.872340 (-7125 2825);
PAINT AQUA (-7125 2825);
DISPLAY INVISIBLE (-7125 2825);
FORCEPROP 2 LAST CDS_LIB logical_power
J 0
(-7200 2825);
DISPLAY INVISIBLE (-7200 2825);
FORCEADD UNIVERSAL_POWER..1
(-8725 3800);
FORCEPROP 3 LASTPIN (-8725 3750) SIG_NAME P3V3_AUX\g
J 0
(-8715 3760);
DISPLAY 0.659574 (-8715 3760);
PAINT MONO (-8715 3760);
DISPLAY INVISIBLE (-8715 3760);
FORCEPROP 1 LAST HDL_POWER P3V3_AUX
J 1
(-8725 3850);
DISPLAY 0.702128 (-8725 3850);
PAINT GREEN (-8725 3850);
FORCEPROP 1 LAST PATH I48
J 0
(-8675 3825);
DISPLAY 0.872340 (-8675 3825);
PAINT AQUA (-8675 3825);
DISPLAY INVISIBLE (-8675 3825);
FORCEPROP 2 LAST CDS_LIB logical_power
J 0
(-8725 3800);
DISPLAY INVISIBLE (-8725 3800);
FORCEADD UNIVERSAL_POWER..1
(-6725 4825);
FORCEPROP 3 LASTPIN (-6725 4775) SIG_NAME VCCIO4\g
J 0
(-6715 4785);
DISPLAY 0.659574 (-6715 4785);
PAINT MONO (-6715 4785);
DISPLAY INVISIBLE (-6715 4785);
FORCEPROP 1 LAST HDL_POWER VCCIO4
J 1
(-6725 4875);
DISPLAY 0.702128 (-6725 4875);
PAINT GREEN (-6725 4875);
FORCEPROP 2 LAST CDS_LIB logical_power
J 0
(-6725 4825);
DISPLAY INVISIBLE (-6725 4825);
FORCEPROP 1 LAST PATH I53
J 0
(-6675 4850);
DISPLAY 0.872340 (-6675 4850);
PAINT AQUA (-6675 4850);
DISPLAY INVISIBLE (-6675 4850);
FORCEADD UNIVERSAL_GND..1
(-7100 4075);
FORCEPROP 3 LASTPIN (-7100 4125) SIG_NAME GND\g
J 0
(-7090 4135);
DISPLAY 0.659574 (-7090 4135);
PAINT MONO (-7090 4135);
DISPLAY INVISIBLE (-7090 4135);
FORCEPROP 2 LAST CDS_LIB logical_power
J 0
(-7100 4075);
DISPLAY INVISIBLE (-7100 4075);
FORCEPROP 1 LAST PATH I55
J 0
(-7025 4075);
DISPLAY 0.872340 (-7025 4075);
PAINT AQUA (-7025 4075);
DISPLAY INVISIBLE (-7025 4075);
FORCEPROP 1 LAST HDL_POWER GND
J 1
(-7075 4000);
DISPLAY 0.702128 (-7075 4000);
PAINT GREEN (-7075 4000);
DISPLAY INVISIBLE (-7075 4000);
FORCEPROP 2 LAST ROOM IO_SLOT
J 1
(-7325 4150);
DISPLAY 0.744681 (-7325 4150);
DISPLAY INVISIBLE (-7325 4150);
FORCEADD UNIVERSAL_POWER..1
(-575 6175);
FORCEPROP 3 LASTPIN (-575 6125) SIG_NAME VCCIO0\g
J 0
(-565 6135);
DISPLAY 0.659574 (-565 6135);
PAINT MONO (-565 6135);
DISPLAY INVISIBLE (-565 6135);
FORCEPROP 1 LAST HDL_POWER VCCIO0
J 1
(-575 6225);
DISPLAY 0.702128 (-575 6225);
PAINT GREEN (-575 6225);
FORCEPROP 2 LAST CDS_LIB logical_power
J 0
(-575 6175);
DISPLAY INVISIBLE (-575 6175);
FORCEPROP 1 LAST PATH I6
J 0
(-525 6200);
DISPLAY 0.872340 (-525 6200);
PAINT AQUA (-525 6200);
DISPLAY INVISIBLE (-525 6200);
FORCEADD UNIVERSAL_POWER..1
(-8775 5025);
FORCEPROP 3 LASTPIN (-8775 4975) SIG_NAME P3V3_AUX\g
J 0
(-8765 4985);
DISPLAY 0.659574 (-8765 4985);
PAINT MONO (-8765 4985);
DISPLAY INVISIBLE (-8765 4985);
FORCEPROP 1 LAST HDL_POWER P3V3_AUX
J 1
(-8775 5075);
DISPLAY 0.702128 (-8775 5075);
PAINT GREEN (-8775 5075);
FORCEPROP 1 LAST PATH I61
J 0
(-8725 5050);
DISPLAY 0.872340 (-8725 5050);
PAINT AQUA (-8725 5050);
DISPLAY INVISIBLE (-8725 5050);
FORCEPROP 2 LAST CDS_LIB logical_power
J 0
(-8775 5025);
DISPLAY INVISIBLE (-8775 5025);
FORCEADD UNIVERSAL_POWER..1
(-6775 2600);
FORCEPROP 3 LASTPIN (-6775 2550) SIG_NAME VCCIO5\g
J 0
(-6765 2560);
DISPLAY 0.659574 (-6765 2560);
PAINT MONO (-6765 2560);
DISPLAY INVISIBLE (-6765 2560);
FORCEPROP 1 LAST HDL_POWER VCCIO5
J 1
(-6775 2650);
DISPLAY 0.702128 (-6775 2650);
PAINT GREEN (-6775 2650);
FORCEPROP 2 LAST CDS_LIB logical_power
J 0
(-6775 2600);
DISPLAY INVISIBLE (-6775 2600);
FORCEPROP 1 LAST PATH I66
J 0
(-6725 2625);
DISPLAY 0.872340 (-6725 2625);
PAINT AQUA (-6725 2625);
DISPLAY INVISIBLE (-6725 2625);
FORCEADD UNIVERSAL_GND..1
(-7150 1850);
FORCEPROP 3 LASTPIN (-7150 1900) SIG_NAME GND\g
J 0
(-7140 1910);
DISPLAY 0.659574 (-7140 1910);
PAINT MONO (-7140 1910);
DISPLAY INVISIBLE (-7140 1910);
FORCEPROP 2 LAST CDS_LIB logical_power
J 0
(-7150 1850);
DISPLAY INVISIBLE (-7150 1850);
FORCEPROP 1 LAST PATH I68
J 0
(-7075 1850);
DISPLAY 0.872340 (-7075 1850);
PAINT AQUA (-7075 1850);
DISPLAY INVISIBLE (-7075 1850);
FORCEPROP 2 LAST ROOM IO_SLOT
J 1
(-7375 1925);
DISPLAY 0.744681 (-7375 1925);
DISPLAY INVISIBLE (-7375 1925);
FORCEPROP 1 LAST HDL_POWER GND
J 1
(-7125 1775);
DISPLAY 0.702128 (-7125 1775);
PAINT GREEN (-7125 1775);
DISPLAY INVISIBLE (-7125 1775);
FORCEADD UNIVERSAL_GND..1
(-2600 5425);
FORCEPROP 3 LASTPIN (-2600 5475) SIG_NAME GND\g
J 0
(-2590 5485);
DISPLAY 0.659574 (-2590 5485);
PAINT MONO (-2590 5485);
DISPLAY INVISIBLE (-2590 5485);
FORCEPROP 2 LAST CDS_LIB logical_power
J 0
(-2600 5425);
DISPLAY INVISIBLE (-2600 5425);
FORCEPROP 2 LAST ROOM IO_SLOT
J 1
(-2825 5500);
DISPLAY 0.744681 (-2825 5500);
DISPLAY INVISIBLE (-2825 5500);
FORCEPROP 1 LAST HDL_POWER GND
J 1
(-2575 5350);
DISPLAY 0.702128 (-2575 5350);
PAINT GREEN (-2575 5350);
DISPLAY INVISIBLE (-2575 5350);
FORCEPROP 1 LAST PATH I7
J 0
(-2525 5425);
DISPLAY 0.872340 (-2525 5425);
PAINT AQUA (-2525 5425);
DISPLAY INVISIBLE (-2525 5425);
FORCEADD Q_RES..1
(-5100 6075);
FORCEPROP 1 LAST VALUE 0
J 2
(-5125 5975);
DISPLAY 0.510638 (-5125 5975);
PAINT SKYBLUE (-5125 5975);
FORCEPROP 1 LAST TOLERANCE 5%
J 0
(-5100 5975);
DISPLAY 0.510638 (-5100 5975);
PAINT SKYBLUE (-5100 5975);
FORCEPROP 1 LAST WATTAGE 1/16W
J 2
(-5125 5925);
DISPLAY 0.510638 (-5125 5925);
PAINT SKYBLUE (-5125 5925);
FORCEPROP 1 LAST PART_NUMBER CS00002JB13
J 0
(-4950 6100);
DISPLAY 0.510638 (-4950 6100);
PAINT WHITE (-4950 6100);
FORCEPROP 1 LAST MATERIAL CHIP
J 0
(-5100 5925);
DISPLAY 0.510638 (-5100 5925);
PAINT SKYBLUE (-5100 5925);
FORCEPROP 1 LAST PACK_TYPE 0402LF
J 0
(-4975 5925);
DISPLAY 0.510638 (-4975 5925);
PAINT SKYBLUE (-4975 5925);
FORCEPROP 2 LAST CDS_LIB pure_quanta
J 0
(-5100 6075);
DISPLAY INVISIBLE (-5100 6075);
FORCEPROP 1 LAST PATH I71
J 0
(-5150 6225);
DISPLAY 0.978723 (-5150 6225);
PAINT WHITE (-5150 6225);
DISPLAY INVISIBLE (-5150 6225);
FORCEPROP 1 LAST $LOCATION R305
J 0
(-5375 6100);
DISPLAY 0.702128 (-5375 6100);
PAINT AQUA (-5375 6100);
FORCEPROP 0 LAST CDS_LOCATION R305
J 0
(-5375 6150);
DISPLAY 0.680851 (-5375 6150);
DISPLAY INVISIBLE (-5375 6150);
FORCEPROP 0 LAST $SEC 1
J 0
(-5375 6150);
DISPLAY 0.680851 (-5375 6150);
PAINT MONO (-5375 6150);
DISPLAY INVISIBLE (-5375 6150);
FORCEPROP 0 LAST CDS_SEC 1
J 0
(-5375 6150);
DISPLAY 1.021277 (-5375 6150);
DISPLAY INVISIBLE (-5375 6150);
FORCEPROP 1 LASTPIN (-5200 6075) $PN 1
J 0
(-5188 6087);
DISPLAY 0.808511 (-5188 6087);
PAINT WHITE (-5188 6087);
DISPLAY INVISIBLE (-5188 6087);
FORCEPROP 1 LASTPIN (-5000 6075) $PN 2
J 0
(-5038 6087);
DISPLAY 0.808511 (-5038 6087);
PAINT WHITE (-5038 6087);
DISPLAY INVISIBLE (-5038 6087);
FORCEADD Q_RES..1
(-5125 4925);
FORCEPROP 1 LAST VALUE 0
J 2
(-5150 4825);
DISPLAY 0.510638 (-5150 4825);
PAINT SKYBLUE (-5150 4825);
FORCEPROP 1 LAST TOLERANCE 5%
J 0
(-5125 4825);
DISPLAY 0.510638 (-5125 4825);
PAINT SKYBLUE (-5125 4825);
FORCEPROP 1 LAST WATTAGE 1/16W
J 2
(-5150 4775);
DISPLAY 0.510638 (-5150 4775);
PAINT SKYBLUE (-5150 4775);
FORCEPROP 1 LAST MATERIAL CHIP
J 0
(-5125 4775);
DISPLAY 0.510638 (-5125 4775);
PAINT SKYBLUE (-5125 4775);
FORCEPROP 1 LAST PACK_TYPE 0402LF
J 0
(-5000 4775);
DISPLAY 0.510638 (-5000 4775);
PAINT SKYBLUE (-5000 4775);
FORCEPROP 1 LAST PART_NUMBER CS00002JB13
J 0
(-4975 4950);
DISPLAY 0.510638 (-4975 4950);
PAINT WHITE (-4975 4950);
FORCEPROP 1 LAST PATH I72
J 0
(-5175 5075);
DISPLAY 0.978723 (-5175 5075);
PAINT WHITE (-5175 5075);
DISPLAY INVISIBLE (-5175 5075);
FORCEPROP 2 LAST CDS_LIB pure_quanta
J 0
(-5125 4925);
DISPLAY INVISIBLE (-5125 4925);
FORCEPROP 1 LAST $LOCATION R525
J 0
(-5175 4975);
DISPLAY 0.978723 (-5175 4975);
FORCEPROP 1 LASTPIN (-5225 4925) $PN 1
J 0
(-5213 4937);
DISPLAY 0.787234 (-5213 4937);
PAINT MONO (-5213 4937);
FORCEPROP 1 LASTPIN (-5025 4925) $PN 2
J 0
(-5063 4937);
DISPLAY 0.787234 (-5063 4937);
PAINT MONO (-5063 4937);
FORCEPROP 0 LAST CDS_LOCATION R525
J 0
(-5175 5025);
DISPLAY 0.680851 (-5175 5025);
DISPLAY INVISIBLE (-5175 5025);
FORCEPROP 0 LAST $SEC 1
J 0
(-5175 5025);
DISPLAY 0.680851 (-5175 5025);
PAINT MONO (-5175 5025);
DISPLAY INVISIBLE (-5175 5025);
FORCEPROP 0 LAST CDS_SEC 1
J 0
(-5175 5025);
DISPLAY 0.680851 (-5175 5025);
DISPLAY INVISIBLE (-5175 5025);
FORCEADD Q_RES..1
(-5125 3825);
FORCEPROP 1 LAST TOLERANCE 5%
J 0
(-5125 3725);
DISPLAY 0.510638 (-5125 3725);
PAINT SKYBLUE (-5125 3725);
FORCEPROP 1 LAST VALUE 0
J 2
(-5150 3725);
DISPLAY 0.510638 (-5150 3725);
PAINT SKYBLUE (-5150 3725);
FORCEPROP 1 LAST WATTAGE 1/16W
J 2
(-5150 3675);
DISPLAY 0.510638 (-5150 3675);
PAINT SKYBLUE (-5150 3675);
FORCEPROP 1 LAST MATERIAL CHIP
J 0
(-5125 3675);
DISPLAY 0.510638 (-5125 3675);
PAINT SKYBLUE (-5125 3675);
FORCEPROP 1 LAST PACK_TYPE 0402LF
J 0
(-5000 3675);
DISPLAY 0.510638 (-5000 3675);
PAINT SKYBLUE (-5000 3675);
FORCEPROP 1 LAST PART_NUMBER CS00002JB13
J 0
(-4975 3850);
DISPLAY 0.510638 (-4975 3850);
PAINT WHITE (-4975 3850);
FORCEPROP 1 LAST PATH I73
J 0
(-5175 3975);
DISPLAY 0.978723 (-5175 3975);
PAINT WHITE (-5175 3975);
DISPLAY INVISIBLE (-5175 3975);
FORCEPROP 2 LAST CDS_LIB pure_quanta
J 0
(-5125 3825);
DISPLAY INVISIBLE (-5125 3825);
FORCEPROP 1 LAST $LOCATION R304
J 0
(-5175 3875);
DISPLAY 0.978723 (-5175 3875);
FORCEPROP 1 LASTPIN (-5225 3825) $PN 1
J 0
(-5213 3837);
DISPLAY 0.787234 (-5213 3837);
PAINT MONO (-5213 3837);
FORCEPROP 1 LASTPIN (-5025 3825) $PN 2
J 0
(-5063 3837);
DISPLAY 0.787234 (-5063 3837);
PAINT MONO (-5063 3837);
FORCEPROP 0 LAST CDS_LOCATION R304
J 0
(-5175 3925);
DISPLAY 0.680851 (-5175 3925);
DISPLAY INVISIBLE (-5175 3925);
FORCEPROP 0 LAST $SEC 1
J 0
(-5175 3925);
DISPLAY 0.680851 (-5175 3925);
PAINT MONO (-5175 3925);
DISPLAY INVISIBLE (-5175 3925);
FORCEPROP 0 LAST CDS_SEC 1
J 0
(-5175 3925);
DISPLAY 0.680851 (-5175 3925);
DISPLAY INVISIBLE (-5175 3925);
FORCEADD Q_RES..1
(-8250 3475);
FORCEPROP 1 LAST PART_NUMBER CS00002JB13
J 0
(-8100 3500);
DISPLAY 0.510638 (-8100 3500);
PAINT WHITE (-8100 3500);
FORCEPROP 1 LAST PACK_TYPE 0402LF
J 0
(-8125 3325);
DISPLAY 0.510638 (-8125 3325);
PAINT SKYBLUE (-8125 3325);
FORCEPROP 1 LAST MATERIAL CHIP
J 0
(-8250 3325);
DISPLAY 0.510638 (-8250 3325);
PAINT SKYBLUE (-8250 3325);
FORCEPROP 1 LAST WATTAGE 1/16W
J 2
(-8275 3325);
DISPLAY 0.510638 (-8275 3325);
PAINT SKYBLUE (-8275 3325);
FORCEPROP 1 LAST TOLERANCE 5%
J 0
(-8250 3375);
DISPLAY 0.510638 (-8250 3375);
PAINT SKYBLUE (-8250 3375);
FORCEPROP 1 LAST VALUE 0
J 2
(-8275 3375);
DISPLAY 0.510638 (-8275 3375);
PAINT SKYBLUE (-8275 3375);
FORCEPROP 1 LAST PATH I74
J 0
(-8300 3625);
DISPLAY 0.978723 (-8300 3625);
PAINT WHITE (-8300 3625);
DISPLAY INVISIBLE (-8300 3625);
FORCEPROP 2 LAST CDS_LIB pure_quanta
J 0
(-8250 3475);
DISPLAY INVISIBLE (-8250 3475);
FORCEPROP 1 LAST $LOCATION R308
J 0
(-8300 3525);
DISPLAY 0.978723 (-8300 3525);
FORCEPROP 1 LASTPIN (-8350 3475) $PN 1
J 0
(-8338 3487);
DISPLAY 0.787234 (-8338 3487);
PAINT MONO (-8338 3487);
FORCEPROP 1 LASTPIN (-8150 3475) $PN 2
J 0
(-8188 3487);
DISPLAY 0.787234 (-8188 3487);
PAINT MONO (-8188 3487);
FORCEPROP 0 LAST CDS_LOCATION R308
J 0
(-8300 3575);
DISPLAY 0.680851 (-8300 3575);
DISPLAY INVISIBLE (-8300 3575);
FORCEPROP 0 LAST $SEC 1
J 0
(-8300 3575);
DISPLAY 0.680851 (-8300 3575);
PAINT MONO (-8300 3575);
DISPLAY INVISIBLE (-8300 3575);
FORCEPROP 0 LAST CDS_SEC 1
J 0
(-8300 3575);
DISPLAY 0.680851 (-8300 3575);
DISPLAY INVISIBLE (-8300 3575);
FORCEADD Q_RES..1
(-8200 2500);
FORCEPROP 1 LAST PART_NUMBER CS00002JB13
J 0
(-8050 2525);
DISPLAY 0.510638 (-8050 2525);
PAINT WHITE (-8050 2525);
FORCEPROP 1 LAST TOLERANCE 5%
J 0
(-8200 2400);
DISPLAY 0.510638 (-8200 2400);
PAINT SKYBLUE (-8200 2400);
FORCEPROP 1 LAST MATERIAL CHIP
J 0
(-8200 2350);
DISPLAY 0.510638 (-8200 2350);
PAINT SKYBLUE (-8200 2350);
FORCEPROP 1 LAST PACK_TYPE 0402LF
J 0
(-8075 2350);
DISPLAY 0.510638 (-8075 2350);
PAINT SKYBLUE (-8075 2350);
FORCEPROP 1 LAST WATTAGE 1/16W
J 2
(-8225 2350);
DISPLAY 0.510638 (-8225 2350);
PAINT SKYBLUE (-8225 2350);
FORCEPROP 1 LAST VALUE 0
J 2
(-8225 2400);
DISPLAY 0.510638 (-8225 2400);
PAINT SKYBLUE (-8225 2400);
FORCEPROP 1 LAST PATH I75
J 0
(-8250 2650);
DISPLAY 0.978723 (-8250 2650);
PAINT WHITE (-8250 2650);
DISPLAY INVISIBLE (-8250 2650);
FORCEPROP 2 LAST CDS_LIB pure_quanta
J 0
(-8200 2500);
DISPLAY INVISIBLE (-8200 2500);
FORCEPROP 1 LAST $LOCATION R301
J 0
(-8250 2550);
DISPLAY 0.978723 (-8250 2550);
FORCEPROP 1 LASTPIN (-8300 2500) $PN 1
J 0
(-8288 2512);
DISPLAY 0.787234 (-8288 2512);
PAINT MONO (-8288 2512);
FORCEPROP 1 LASTPIN (-8100 2500) $PN 2
J 0
(-8138 2512);
DISPLAY 0.787234 (-8138 2512);
PAINT MONO (-8138 2512);
FORCEPROP 0 LAST CDS_LOCATION R301
J 0
(-8250 2600);
DISPLAY 0.680851 (-8250 2600);
DISPLAY INVISIBLE (-8250 2600);
FORCEPROP 0 LAST $SEC 1
J 0
(-8250 2600);
DISPLAY 0.680851 (-8250 2600);
PAINT MONO (-8250 2600);
DISPLAY INVISIBLE (-8250 2600);
FORCEPROP 0 LAST CDS_SEC 1
J 0
(-8250 2600);
DISPLAY 0.680851 (-8250 2600);
DISPLAY INVISIBLE (-8250 2600);
FORCEADD Q_RES..1
(-8575 4725);
FORCEPROP 1 LAST TOLERANCE 5%
J 0
(-8575 4625);
DISPLAY 0.510638 (-8575 4625);
PAINT SKYBLUE (-8575 4625);
FORCEPROP 1 LAST VALUE 0
J 2
(-8600 4625);
DISPLAY 0.510638 (-8600 4625);
PAINT SKYBLUE (-8600 4625);
FORCEPROP 1 LAST PACK_TYPE 0402LF
J 0
(-8450 4575);
DISPLAY 0.510638 (-8450 4575);
PAINT SKYBLUE (-8450 4575);
FORCEPROP 1 LAST MATERIAL CHIP
J 0
(-8575 4575);
DISPLAY 0.510638 (-8575 4575);
PAINT SKYBLUE (-8575 4575);
FORCEPROP 1 LAST WATTAGE 1/16W
J 2
(-8600 4575);
DISPLAY 0.510638 (-8600 4575);
PAINT SKYBLUE (-8600 4575);
FORCEPROP 1 LAST PART_NUMBER CS00002JB13
J 0
(-8425 4750);
DISPLAY 0.510638 (-8425 4750);
PAINT WHITE (-8425 4750);
FORCEPROP 1 LAST PATH I76
J 0
(-8625 4875);
DISPLAY 0.978723 (-8625 4875);
PAINT WHITE (-8625 4875);
DISPLAY INVISIBLE (-8625 4875);
FORCEPROP 2 LAST CDS_LIB pure_quanta
J 0
(-8575 4725);
DISPLAY INVISIBLE (-8575 4725);
FORCEPROP 1 LAST $LOCATION R307
J 0
(-8625 4775);
DISPLAY 0.978723 (-8625 4775);
FORCEPROP 1 LASTPIN (-8675 4725) $PN 1
J 0
(-8663 4737);
DISPLAY 0.787234 (-8663 4737);
PAINT MONO (-8663 4737);
FORCEPROP 1 LASTPIN (-8475 4725) $PN 2
J 0
(-8513 4737);
DISPLAY 0.787234 (-8513 4737);
PAINT MONO (-8513 4737);
FORCEPROP 0 LAST CDS_LOCATION R307
J 0
(-8625 4825);
DISPLAY 0.680851 (-8625 4825);
DISPLAY INVISIBLE (-8625 4825);
FORCEPROP 0 LAST $SEC 1
J 0
(-8625 4825);
DISPLAY 0.680851 (-8625 4825);
PAINT MONO (-8625 4825);
DISPLAY INVISIBLE (-8625 4825);
FORCEPROP 0 LAST CDS_SEC 1
J 0
(-8625 4825);
DISPLAY 0.680851 (-8625 4825);
DISPLAY INVISIBLE (-8625 4825);
FORCEADD Q_CAP..1
(-3400 5850);
FORCEPROP 1 LAST PART_NUMBER CH4104K1B00
J 0
(-3350 5700);
DISPLAY 0.978723 (-3350 5700);
FORCEPROP 1 LAST VALUE 0.1UF
J 0
(-3350 5900);
DISPLAY 0.978723 (-3350 5900);
FORCEPROP 1 LAST VOLTAGE 25V
J 0
(-3350 5850);
DISPLAY 0.978723 (-3350 5850);
FORCEPROP 1 LAST TOLERANCE 10%
J 0
(-3350 5800);
DISPLAY 0.978723 (-3350 5800);
FORCEPROP 1 LAST MATERIAL X7R
J 0
(-3350 5750);
DISPLAY 0.978723 (-3350 5750);
FORCEPROP 1 LAST PACK_TYPE 0402
J 0
(-3350 5650);
DISPLAY 0.978723 (-3350 5650);
FORCEPROP 1 LAST PATH I77
J 0
(-3350 6000);
DISPLAY 0.978723 (-3350 6000);
PAINT WHITE (-3350 6000);
DISPLAY INVISIBLE (-3350 6000);
FORCEPROP 2 LAST CDS_LIB pure_quanta
J 0
(-3400 5850);
DISPLAY INVISIBLE (-3400 5850);
FORCEPROP 1 LAST $LOCATION C247
J 0
(-3350 5950);
DISPLAY 0.978723 (-3350 5950);
FORCEPROP 1 LASTPIN (-3400 5950) $PN 1
J 0
(-3390 5930);
DISPLAY 0.787234 (-3390 5930);
PAINT MONO (-3390 5930);
FORCEPROP 1 LASTPIN (-3400 5750) $PN 2
J 0
(-3390 5730);
DISPLAY 0.787234 (-3390 5730);
PAINT MONO (-3390 5730);
FORCEPROP 0 LAST CDS_LOCATION C247
J 0
(-3350 6000);
DISPLAY 0.680851 (-3350 6000);
DISPLAY INVISIBLE (-3350 6000);
FORCEPROP 0 LAST $SEC 1
J 0
(-3350 6000);
DISPLAY 0.680851 (-3350 6000);
PAINT MONO (-3350 6000);
DISPLAY INVISIBLE (-3350 6000);
FORCEPROP 0 LAST CDS_SEC 1
J 0
(-3350 6000);
DISPLAY 0.680851 (-3350 6000);
DISPLAY INVISIBLE (-3350 6000);
FORCEADD Q_CAP..1
(-2825 5850);
FORCEPROP 1 LAST TOLERANCE 10%
J 0
(-2775 5800);
DISPLAY 0.978723 (-2775 5800);
FORCEPROP 1 LAST PART_NUMBER CH4104K1B00
J 0
(-2775 5700);
DISPLAY 0.978723 (-2775 5700);
FORCEPROP 1 LAST VOLTAGE 25V
J 0
(-2775 5850);
DISPLAY 0.978723 (-2775 5850);
FORCEPROP 1 LAST VALUE 0.1UF
J 0
(-2775 5900);
DISPLAY 0.978723 (-2775 5900);
FORCEPROP 1 LAST PACK_TYPE 0402
J 0
(-2775 5650);
DISPLAY 0.978723 (-2775 5650);
FORCEPROP 1 LAST MATERIAL X7R
J 0
(-2775 5750);
DISPLAY 0.978723 (-2775 5750);
FORCEPROP 2 LAST CDS_LIB pure_quanta
J 0
(-2825 5850);
DISPLAY INVISIBLE (-2825 5850);
FORCEPROP 1 LAST PATH I78
J 0
(-2775 6000);
DISPLAY 0.978723 (-2775 6000);
PAINT WHITE (-2775 6000);
DISPLAY INVISIBLE (-2775 6000);
FORCEPROP 1 LAST $LOCATION C189
J 0
(-2775 5950);
DISPLAY 0.978723 (-2775 5950);
FORCEPROP 1 LASTPIN (-2825 5950) $PN 1
J 0
(-2815 5930);
DISPLAY 0.787234 (-2815 5930);
PAINT MONO (-2815 5930);
FORCEPROP 1 LASTPIN (-2825 5750) $PN 2
J 0
(-2815 5730);
DISPLAY 0.787234 (-2815 5730);
PAINT MONO (-2815 5730);
FORCEPROP 0 LAST CDS_LOCATION C189
J 0
(-2775 6000);
DISPLAY 0.680851 (-2775 6000);
DISPLAY INVISIBLE (-2775 6000);
FORCEPROP 0 LAST $SEC 1
J 0
(-2775 6000);
DISPLAY 0.680851 (-2775 6000);
PAINT MONO (-2775 6000);
DISPLAY INVISIBLE (-2775 6000);
FORCEPROP 0 LAST CDS_SEC 1
J 0
(-2775 6000);
DISPLAY 0.680851 (-2775 6000);
DISPLAY INVISIBLE (-2775 6000);
FORCEADD Q_CAP..1
(-2250 5850);
FORCEPROP 1 LAST VALUE 0.1UF
J 0
(-2200 5900);
DISPLAY 0.978723 (-2200 5900);
FORCEPROP 1 LAST MATERIAL X7R
J 0
(-2200 5750);
DISPLAY 0.978723 (-2200 5750);
FORCEPROP 1 LAST TOLERANCE 10%
J 0
(-2200 5800);
DISPLAY 0.978723 (-2200 5800);
FORCEPROP 1 LAST VOLTAGE 25V
J 0
(-2200 5850);
DISPLAY 0.978723 (-2200 5850);
FORCEPROP 1 LAST PART_NUMBER CH4104K1B00
J 0
(-2200 5700);
DISPLAY 0.978723 (-2200 5700);
FORCEPROP 1 LAST PACK_TYPE 0402
J 0
(-2200 5650);
DISPLAY 0.978723 (-2200 5650);
FORCEPROP 1 LAST PATH I79
J 0
(-2200 6000);
DISPLAY 0.978723 (-2200 6000);
PAINT WHITE (-2200 6000);
DISPLAY INVISIBLE (-2200 6000);
FORCEPROP 2 LAST CDS_LIB pure_quanta
J 0
(-2250 5850);
DISPLAY INVISIBLE (-2250 5850);
FORCEPROP 1 LAST $LOCATION C261
J 0
(-2200 5950);
DISPLAY 0.978723 (-2200 5950);
FORCEPROP 1 LASTPIN (-2250 5950) $PN 1
J 0
(-2240 5930);
DISPLAY 0.787234 (-2240 5930);
PAINT MONO (-2240 5930);
FORCEPROP 1 LASTPIN (-2250 5750) $PN 2
J 0
(-2240 5730);
DISPLAY 0.787234 (-2240 5730);
PAINT MONO (-2240 5730);
FORCEPROP 0 LAST CDS_LOCATION C261
J 0
(-2200 6000);
DISPLAY 0.680851 (-2200 6000);
DISPLAY INVISIBLE (-2200 6000);
FORCEPROP 0 LAST $SEC 1
J 0
(-2200 6000);
DISPLAY 0.680851 (-2200 6000);
PAINT MONO (-2200 6000);
DISPLAY INVISIBLE (-2200 6000);
FORCEPROP 0 LAST CDS_SEC 1
J 0
(-2200 6000);
DISPLAY 0.680851 (-2200 6000);
DISPLAY INVISIBLE (-2200 6000);
FORCEADD Q_CAP..1
(-4700 5875);
FORCEPROP 1 LAST PART_NUMBER CH5104KEB02
J 0
(-4650 5725);
DISPLAY 0.978723 (-4650 5725);
FORCEPROP 1 LAST PACK_TYPE C0402
J 0
(-4650 5675);
DISPLAY 0.978723 (-4650 5675);
FORCEPROP 1 LAST VALUE 1UF
J 0
(-4650 5925);
DISPLAY 0.978723 (-4650 5925);
FORCEPROP 1 LAST VOLTAGE 25V
J 0
(-4650 5875);
DISPLAY 0.978723 (-4650 5875);
FORCEPROP 1 LAST TOLERANCE 10%
J 0
(-4650 5825);
DISPLAY 0.978723 (-4650 5825);
FORCEPROP 1 LAST MATERIAL X6S
J 0
(-4650 5775);
DISPLAY 0.978723 (-4650 5775);
FORCEPROP 1 LAST PATH I8
J 0
(-4650 6025);
DISPLAY 0.978723 (-4650 6025);
PAINT WHITE (-4650 6025);
DISPLAY INVISIBLE (-4650 6025);
FORCEPROP 2 LAST CDS_LIB pure_quanta
J 0
(-4700 5875);
DISPLAY INVISIBLE (-4700 5875);
FORCEPROP 1 LAST $LOCATION C166
J 0
(-4650 5975);
DISPLAY 0.978723 (-4650 5975);
FORCEPROP 1 LASTPIN (-4700 5975) $PN 1
J 0
(-4690 5955);
DISPLAY 0.787234 (-4690 5955);
PAINT MONO (-4690 5955);
FORCEPROP 1 LASTPIN (-4700 5775) $PN 2
J 0
(-4690 5755);
DISPLAY 0.787234 (-4690 5755);
PAINT MONO (-4690 5755);
FORCEPROP 0 LAST CDS_LOCATION C166
J 0
(-4650 6025);
DISPLAY 0.680851 (-4650 6025);
DISPLAY INVISIBLE (-4650 6025);
FORCEPROP 0 LAST $SEC 1
J 0
(-4650 6025);
DISPLAY 0.680851 (-4650 6025);
PAINT MONO (-4650 6025);
DISPLAY INVISIBLE (-4650 6025);
FORCEPROP 0 LAST CDS_SEC 1
J 0
(-4650 6025);
DISPLAY 0.680851 (-4650 6025);
DISPLAY INVISIBLE (-4650 6025);
FORCEADD Q_CAP..1
(-4050 4700);
FORCEPROP 1 LAST VALUE 0.1UF
J 0
(-4000 4750);
DISPLAY 0.978723 (-4000 4750);
FORCEPROP 1 LAST MATERIAL X7R
J 0
(-4000 4600);
DISPLAY 0.978723 (-4000 4600);
FORCEPROP 1 LAST TOLERANCE 10%
J 0
(-4000 4650);
DISPLAY 0.978723 (-4000 4650);
FORCEPROP 1 LAST VOLTAGE 25V
J 0
(-4000 4700);
DISPLAY 0.978723 (-4000 4700);
FORCEPROP 1 LAST PACK_TYPE 0402
J 0
(-4000 4500);
DISPLAY 0.978723 (-4000 4500);
FORCEPROP 1 LAST PART_NUMBER CH4104K1B00
J 0
(-4000 4550);
DISPLAY 0.978723 (-4000 4550);
FORCEPROP 1 LAST PATH I80
J 0
(-4000 4850);
DISPLAY 0.978723 (-4000 4850);
PAINT WHITE (-4000 4850);
DISPLAY INVISIBLE (-4000 4850);
FORCEPROP 2 LAST CDS_LIB pure_quanta
J 0
(-4050 4700);
DISPLAY INVISIBLE (-4050 4700);
FORCEPROP 1 LAST $LOCATION C167
J 0
(-4000 4800);
DISPLAY 0.978723 (-4000 4800);
FORCEPROP 1 LASTPIN (-4050 4800) $PN 1
J 0
(-4040 4780);
DISPLAY 0.787234 (-4040 4780);
PAINT MONO (-4040 4780);
FORCEPROP 1 LASTPIN (-4050 4600) $PN 2
J 0
(-4040 4580);
DISPLAY 0.787234 (-4040 4580);
PAINT MONO (-4040 4580);
FORCEPROP 0 LAST CDS_LOCATION C167
J 0
(-4000 4850);
DISPLAY 0.680851 (-4000 4850);
DISPLAY INVISIBLE (-4000 4850);
FORCEPROP 0 LAST $SEC 1
J 0
(-4000 4850);
DISPLAY 0.680851 (-4000 4850);
PAINT MONO (-4000 4850);
DISPLAY INVISIBLE (-4000 4850);
FORCEPROP 0 LAST CDS_SEC 1
J 0
(-4000 4850);
DISPLAY 0.680851 (-4000 4850);
DISPLAY INVISIBLE (-4000 4850);
FORCEADD Q_CAP..1
(-3450 4700);
FORCEPROP 1 LAST PACK_TYPE 0402
J 0
(-3400 4500);
DISPLAY 0.978723 (-3400 4500);
FORCEPROP 1 LAST MATERIAL X7R
J 0
(-3400 4600);
DISPLAY 0.978723 (-3400 4600);
FORCEPROP 1 LAST TOLERANCE 10%
J 0
(-3400 4650);
DISPLAY 0.978723 (-3400 4650);
FORCEPROP 1 LAST VOLTAGE 25V
J 0
(-3400 4700);
DISPLAY 0.978723 (-3400 4700);
FORCEPROP 1 LAST VALUE 0.1UF
J 0
(-3400 4750);
DISPLAY 0.978723 (-3400 4750);
FORCEPROP 1 LAST PART_NUMBER CH4104K1B00
J 0
(-3400 4550);
DISPLAY 0.978723 (-3400 4550);
FORCEPROP 2 LAST CDS_LIB pure_quanta
J 0
(-3450 4700);
DISPLAY INVISIBLE (-3450 4700);
FORCEPROP 1 LAST PATH I81
J 0
(-3400 4850);
DISPLAY 0.978723 (-3400 4850);
PAINT WHITE (-3400 4850);
DISPLAY INVISIBLE (-3400 4850);
FORCEPROP 1 LAST $LOCATION C243
J 0
(-3400 4800);
DISPLAY 0.978723 (-3400 4800);
FORCEPROP 1 LASTPIN (-3450 4800) $PN 1
J 0
(-3440 4780);
DISPLAY 0.787234 (-3440 4780);
PAINT MONO (-3440 4780);
FORCEPROP 1 LASTPIN (-3450 4600) $PN 2
J 0
(-3440 4580);
DISPLAY 0.787234 (-3440 4580);
PAINT MONO (-3440 4580);
FORCEPROP 0 LAST CDS_LOCATION C243
J 0
(-3400 4850);
DISPLAY 0.680851 (-3400 4850);
DISPLAY INVISIBLE (-3400 4850);
FORCEPROP 0 LAST $SEC 1
J 0
(-3400 4850);
DISPLAY 0.680851 (-3400 4850);
PAINT MONO (-3400 4850);
DISPLAY INVISIBLE (-3400 4850);
FORCEPROP 0 LAST CDS_SEC 1
J 0
(-3400 4850);
DISPLAY 0.680851 (-3400 4850);
DISPLAY INVISIBLE (-3400 4850);
FORCEADD Q_CAP..1
(-2875 4700);
FORCEPROP 1 LAST TOLERANCE 10%
J 0
(-2825 4650);
DISPLAY 0.978723 (-2825 4650);
FORCEPROP 1 LAST PART_NUMBER CH4104K1B00
J 0
(-2825 4550);
DISPLAY 0.978723 (-2825 4550);
FORCEPROP 1 LAST PACK_TYPE 0402
J 0
(-2825 4500);
DISPLAY 0.978723 (-2825 4500);
FORCEPROP 1 LAST MATERIAL X7R
J 0
(-2825 4600);
DISPLAY 0.978723 (-2825 4600);
FORCEPROP 1 LAST VALUE 0.1UF
J 0
(-2825 4750);
DISPLAY 0.978723 (-2825 4750);
FORCEPROP 1 LAST VOLTAGE 25V
J 0
(-2825 4700);
DISPLAY 0.978723 (-2825 4700);
FORCEPROP 2 LAST CDS_LIB pure_quanta
J 0
(-2875 4700);
DISPLAY INVISIBLE (-2875 4700);
FORCEPROP 1 LAST PATH I82
J 0
(-2825 4850);
DISPLAY 0.978723 (-2825 4850);
PAINT WHITE (-2825 4850);
DISPLAY INVISIBLE (-2825 4850);
FORCEPROP 1 LAST $LOCATION C254
J 0
(-2825 4800);
DISPLAY 0.978723 (-2825 4800);
FORCEPROP 1 LASTPIN (-2875 4800) $PN 1
J 0
(-2865 4780);
DISPLAY 0.787234 (-2865 4780);
PAINT MONO (-2865 4780);
FORCEPROP 1 LASTPIN (-2875 4600) $PN 2
J 0
(-2865 4580);
DISPLAY 0.787234 (-2865 4580);
PAINT MONO (-2865 4580);
FORCEPROP 0 LAST CDS_LOCATION C254
J 0
(-2825 4850);
DISPLAY 0.680851 (-2825 4850);
DISPLAY INVISIBLE (-2825 4850);
FORCEPROP 0 LAST $SEC 1
J 0
(-2825 4850);
DISPLAY 0.680851 (-2825 4850);
PAINT MONO (-2825 4850);
DISPLAY INVISIBLE (-2825 4850);
FORCEPROP 0 LAST CDS_SEC 1
J 0
(-2825 4850);
DISPLAY 0.680851 (-2825 4850);
DISPLAY INVISIBLE (-2825 4850);
FORCEADD Q_CAP..1
(-2300 4700);
FORCEPROP 1 LAST PART_NUMBER CH4104K1B00
J 0
(-2250 4550);
DISPLAY 0.978723 (-2250 4550);
FORCEPROP 1 LAST PACK_TYPE 0402
J 0
(-2250 4500);
DISPLAY 0.978723 (-2250 4500);
FORCEPROP 1 LAST MATERIAL X7R
J 0
(-2250 4600);
DISPLAY 0.978723 (-2250 4600);
FORCEPROP 1 LAST VOLTAGE 25V
J 0
(-2250 4700);
DISPLAY 0.978723 (-2250 4700);
FORCEPROP 1 LAST TOLERANCE 10%
J 0
(-2250 4650);
DISPLAY 0.978723 (-2250 4650);
FORCEPROP 1 LAST VALUE 0.1UF
J 0
(-2250 4750);
DISPLAY 0.978723 (-2250 4750);
FORCEPROP 2 LAST CDS_LIB pure_quanta
J 0
(-2300 4700);
DISPLAY INVISIBLE (-2300 4700);
FORCEPROP 1 LAST PATH I83
J 0
(-2250 4850);
DISPLAY 0.978723 (-2250 4850);
PAINT WHITE (-2250 4850);
DISPLAY INVISIBLE (-2250 4850);
FORCEPROP 1 LAST $LOCATION C141
J 0
(-2250 4800);
DISPLAY 0.978723 (-2250 4800);
FORCEPROP 1 LASTPIN (-2300 4800) $PN 1
J 0
(-2290 4780);
DISPLAY 0.787234 (-2290 4780);
PAINT MONO (-2290 4780);
FORCEPROP 1 LASTPIN (-2300 4600) $PN 2
J 0
(-2290 4580);
DISPLAY 0.787234 (-2290 4580);
PAINT MONO (-2290 4580);
FORCEPROP 0 LAST CDS_LOCATION C141
J 0
(-2250 4850);
DISPLAY 0.680851 (-2250 4850);
DISPLAY INVISIBLE (-2250 4850);
FORCEPROP 0 LAST $SEC 1
J 0
(-2250 4850);
DISPLAY 0.680851 (-2250 4850);
PAINT MONO (-2250 4850);
DISPLAY INVISIBLE (-2250 4850);
FORCEPROP 0 LAST CDS_SEC 1
J 0
(-2250 4850);
DISPLAY 0.680851 (-2250 4850);
DISPLAY INVISIBLE (-2250 4850);
FORCEADD Q_CAP..1
(-4050 3600);
FORCEPROP 1 LAST PART_NUMBER CH4104K1B00
J 0
(-4000 3450);
DISPLAY 0.978723 (-4000 3450);
FORCEPROP 1 LAST MATERIAL X7R
J 0
(-4000 3500);
DISPLAY 0.978723 (-4000 3500);
FORCEPROP 1 LAST TOLERANCE 10%
J 0
(-4000 3550);
DISPLAY 0.978723 (-4000 3550);
FORCEPROP 1 LAST PACK_TYPE 0402
J 0
(-4000 3400);
DISPLAY 0.978723 (-4000 3400);
FORCEPROP 1 LAST VALUE 0.1UF
J 0
(-4000 3650);
DISPLAY 0.978723 (-4000 3650);
FORCEPROP 1 LAST VOLTAGE 25V
J 0
(-4000 3600);
DISPLAY 0.978723 (-4000 3600);
FORCEPROP 1 LAST PATH I84
J 0
(-4000 3750);
DISPLAY 0.978723 (-4000 3750);
PAINT WHITE (-4000 3750);
DISPLAY INVISIBLE (-4000 3750);
FORCEPROP 2 LAST CDS_LIB pure_quanta
J 0
(-4050 3600);
DISPLAY INVISIBLE (-4050 3600);
FORCEPROP 1 LAST $LOCATION C187
J 0
(-4000 3700);
DISPLAY 0.978723 (-4000 3700);
FORCEPROP 1 LASTPIN (-4050 3700) $PN 1
J 0
(-4040 3680);
DISPLAY 0.787234 (-4040 3680);
PAINT MONO (-4040 3680);
FORCEPROP 1 LASTPIN (-4050 3500) $PN 2
J 0
(-4040 3480);
DISPLAY 0.787234 (-4040 3480);
PAINT MONO (-4040 3480);
FORCEPROP 0 LAST CDS_LOCATION C187
J 0
(-4000 3750);
DISPLAY 0.680851 (-4000 3750);
DISPLAY INVISIBLE (-4000 3750);
FORCEPROP 0 LAST $SEC 1
J 0
(-4000 3750);
DISPLAY 0.680851 (-4000 3750);
PAINT MONO (-4000 3750);
DISPLAY INVISIBLE (-4000 3750);
FORCEPROP 0 LAST CDS_SEC 1
J 0
(-4000 3750);
DISPLAY 0.680851 (-4000 3750);
DISPLAY INVISIBLE (-4000 3750);
FORCEADD Q_CAP..1
(-3425 3600);
FORCEPROP 1 LAST PART_NUMBER CH4104K1B00
J 0
(-3375 3450);
DISPLAY 0.978723 (-3375 3450);
FORCEPROP 1 LAST VOLTAGE 25V
J 0
(-3375 3600);
DISPLAY 0.978723 (-3375 3600);
FORCEPROP 1 LAST VALUE 0.1UF
J 0
(-3375 3650);
DISPLAY 0.978723 (-3375 3650);
FORCEPROP 1 LAST TOLERANCE 10%
J 0
(-3375 3550);
DISPLAY 0.978723 (-3375 3550);
FORCEPROP 1 LAST MATERIAL X7R
J 0
(-3375 3500);
DISPLAY 0.978723 (-3375 3500);
FORCEPROP 1 LAST PACK_TYPE 0402
J 0
(-3375 3400);
DISPLAY 0.978723 (-3375 3400);
FORCEPROP 1 LAST PATH I85
J 0
(-3375 3750);
DISPLAY 0.978723 (-3375 3750);
PAINT WHITE (-3375 3750);
DISPLAY INVISIBLE (-3375 3750);
FORCEPROP 2 LAST CDS_LIB pure_quanta
J 0
(-3425 3600);
DISPLAY INVISIBLE (-3425 3600);
FORCEPROP 1 LAST $LOCATION C245
J 0
(-3375 3700);
DISPLAY 0.978723 (-3375 3700);
FORCEPROP 1 LASTPIN (-3425 3700) $PN 1
J 0
(-3415 3680);
DISPLAY 0.787234 (-3415 3680);
PAINT MONO (-3415 3680);
FORCEPROP 1 LASTPIN (-3425 3500) $PN 2
J 0
(-3415 3480);
DISPLAY 0.787234 (-3415 3480);
PAINT MONO (-3415 3480);
FORCEPROP 0 LAST CDS_LOCATION C245
J 0
(-3375 3750);
DISPLAY 0.680851 (-3375 3750);
DISPLAY INVISIBLE (-3375 3750);
FORCEPROP 0 LAST $SEC 1
J 0
(-3375 3750);
DISPLAY 0.680851 (-3375 3750);
PAINT MONO (-3375 3750);
DISPLAY INVISIBLE (-3375 3750);
FORCEPROP 0 LAST CDS_SEC 1
J 0
(-3375 3750);
DISPLAY 0.680851 (-3375 3750);
DISPLAY INVISIBLE (-3375 3750);
FORCEADD Q_CAP..1
(-2850 3600);
FORCEPROP 1 LAST VALUE 0.1UF
J 0
(-2800 3650);
DISPLAY 0.978723 (-2800 3650);
FORCEPROP 1 LAST MATERIAL X7R
J 0
(-2800 3500);
DISPLAY 0.978723 (-2800 3500);
FORCEPROP 1 LAST TOLERANCE 10%
J 0
(-2800 3550);
DISPLAY 0.978723 (-2800 3550);
FORCEPROP 1 LAST VOLTAGE 25V
J 0
(-2800 3600);
DISPLAY 0.978723 (-2800 3600);
FORCEPROP 1 LAST PART_NUMBER CH4104K1B00
J 0
(-2800 3450);
DISPLAY 0.978723 (-2800 3450);
FORCEPROP 1 LAST PACK_TYPE 0402
J 0
(-2800 3400);
DISPLAY 0.978723 (-2800 3400);
FORCEPROP 2 LAST CDS_LIB pure_quanta
J 0
(-2850 3600);
DISPLAY INVISIBLE (-2850 3600);
FORCEPROP 1 LAST PATH I86
J 0
(-2800 3750);
DISPLAY 0.978723 (-2800 3750);
PAINT WHITE (-2800 3750);
DISPLAY INVISIBLE (-2800 3750);
FORCEPROP 1 LAST $LOCATION C188
J 0
(-2800 3700);
DISPLAY 0.978723 (-2800 3700);
FORCEPROP 1 LASTPIN (-2850 3700) $PN 1
J 0
(-2840 3680);
DISPLAY 0.787234 (-2840 3680);
PAINT MONO (-2840 3680);
FORCEPROP 1 LASTPIN (-2850 3500) $PN 2
J 0
(-2840 3480);
DISPLAY 0.787234 (-2840 3480);
PAINT MONO (-2840 3480);
FORCEPROP 0 LAST CDS_LOCATION C188
J 0
(-2800 3750);
DISPLAY 0.680851 (-2800 3750);
DISPLAY INVISIBLE (-2800 3750);
FORCEPROP 0 LAST $SEC 1
J 0
(-2800 3750);
DISPLAY 0.680851 (-2800 3750);
PAINT MONO (-2800 3750);
DISPLAY INVISIBLE (-2800 3750);
FORCEPROP 0 LAST CDS_SEC 1
J 0
(-2800 3750);
DISPLAY 0.680851 (-2800 3750);
DISPLAY INVISIBLE (-2800 3750);
FORCEADD Q_CAP..1
(-2275 3600);
FORCEPROP 1 LAST TOLERANCE 10%
J 0
(-2225 3550);
DISPLAY 0.978723 (-2225 3550);
FORCEPROP 1 LAST VALUE 0.1UF
J 0
(-2225 3650);
DISPLAY 0.978723 (-2225 3650);
FORCEPROP 1 LAST PART_NUMBER CH4104K1B00
J 0
(-2225 3450);
DISPLAY 0.978723 (-2225 3450);
FORCEPROP 1 LAST PACK_TYPE 0402
J 0
(-2225 3400);
DISPLAY 0.978723 (-2225 3400);
FORCEPROP 1 LAST VOLTAGE 25V
J 0
(-2225 3600);
DISPLAY 0.978723 (-2225 3600);
FORCEPROP 1 LAST MATERIAL X7R
J 0
(-2225 3500);
DISPLAY 0.978723 (-2225 3500);
FORCEPROP 2 LAST CDS_LIB pure_quanta
J 0
(-2275 3600);
DISPLAY INVISIBLE (-2275 3600);
FORCEPROP 1 LAST PATH I87
J 0
(-2225 3750);
DISPLAY 0.978723 (-2225 3750);
PAINT WHITE (-2225 3750);
DISPLAY INVISIBLE (-2225 3750);
FORCEPROP 1 LAST $LOCATION C260
J 0
(-2225 3700);
DISPLAY 0.978723 (-2225 3700);
FORCEPROP 1 LASTPIN (-2275 3700) $PN 1
J 0
(-2265 3680);
DISPLAY 0.787234 (-2265 3680);
PAINT MONO (-2265 3680);
FORCEPROP 1 LASTPIN (-2275 3500) $PN 2
J 0
(-2265 3480);
DISPLAY 0.787234 (-2265 3480);
PAINT MONO (-2265 3480);
FORCEPROP 0 LAST CDS_LOCATION C260
J 0
(-2225 3750);
DISPLAY 0.680851 (-2225 3750);
DISPLAY INVISIBLE (-2225 3750);
FORCEPROP 0 LAST $SEC 1
J 0
(-2225 3750);
DISPLAY 0.680851 (-2225 3750);
PAINT MONO (-2225 3750);
DISPLAY INVISIBLE (-2225 3750);
FORCEPROP 0 LAST CDS_SEC 1
J 0
(-2225 3750);
DISPLAY 0.680851 (-2225 3750);
DISPLAY INVISIBLE (-2225 3750);
FORCEADD Q_CAP..1
(-7200 3250);
FORCEPROP 1 LAST PART_NUMBER CH4104K1B00
J 0
(-7150 3100);
DISPLAY 0.978723 (-7150 3100);
FORCEPROP 1 LAST VALUE 0.1UF
J 0
(-7150 3300);
DISPLAY 0.978723 (-7150 3300);
FORCEPROP 1 LAST MATERIAL X7R
J 0
(-7150 3150);
DISPLAY 0.978723 (-7150 3150);
FORCEPROP 1 LAST TOLERANCE 10%
J 0
(-7150 3200);
DISPLAY 0.978723 (-7150 3200);
FORCEPROP 1 LAST VOLTAGE 25V
J 0
(-7150 3250);
DISPLAY 0.978723 (-7150 3250);
FORCEPROP 1 LAST PACK_TYPE 0402
J 0
(-7150 3050);
DISPLAY 0.978723 (-7150 3050);
FORCEPROP 1 LAST PATH I88
J 0
(-7150 3400);
DISPLAY 0.978723 (-7150 3400);
PAINT WHITE (-7150 3400);
DISPLAY INVISIBLE (-7150 3400);
FORCEPROP 2 LAST CDS_LIB pure_quanta
J 0
(-7200 3250);
DISPLAY INVISIBLE (-7200 3250);
FORCEPROP 1 LAST $LOCATION C152
J 0
(-7150 3350);
DISPLAY 0.978723 (-7150 3350);
FORCEPROP 1 LASTPIN (-7200 3350) $PN 1
J 0
(-7190 3330);
DISPLAY 0.787234 (-7190 3330);
PAINT MONO (-7190 3330);
FORCEPROP 1 LASTPIN (-7200 3150) $PN 2
J 0
(-7190 3130);
DISPLAY 0.787234 (-7190 3130);
PAINT MONO (-7190 3130);
FORCEPROP 0 LAST CDS_LOCATION C152
J 0
(-7150 3400);
DISPLAY 0.680851 (-7150 3400);
DISPLAY INVISIBLE (-7150 3400);
FORCEPROP 0 LAST $SEC 1
J 0
(-7150 3400);
DISPLAY 0.680851 (-7150 3400);
PAINT MONO (-7150 3400);
DISPLAY INVISIBLE (-7150 3400);
FORCEPROP 0 LAST CDS_SEC 1
J 0
(-7150 3400);
DISPLAY 0.680851 (-7150 3400);
DISPLAY INVISIBLE (-7150 3400);
FORCEADD Q_CAP..1
(-7150 2275);
FORCEPROP 1 LAST VOLTAGE 25V
J 0
(-7100 2275);
DISPLAY 0.978723 (-7100 2275);
FORCEPROP 1 LAST PACK_TYPE 0402
J 0
(-7100 2075);
DISPLAY 0.978723 (-7100 2075);
FORCEPROP 1 LAST MATERIAL X7R
J 0
(-7100 2175);
DISPLAY 0.978723 (-7100 2175);
FORCEPROP 1 LAST TOLERANCE 10%
J 0
(-7100 2225);
DISPLAY 0.978723 (-7100 2225);
FORCEPROP 1 LAST VALUE 0.1UF
J 0
(-7100 2325);
DISPLAY 0.978723 (-7100 2325);
FORCEPROP 1 LAST PART_NUMBER CH4104K1B00
J 0
(-7100 2125);
DISPLAY 0.978723 (-7100 2125);
FORCEPROP 1 LAST PATH I89
J 0
(-7100 2425);
DISPLAY 0.978723 (-7100 2425);
PAINT WHITE (-7100 2425);
DISPLAY INVISIBLE (-7100 2425);
FORCEPROP 2 LAST CDS_LIB pure_quanta
J 0
(-7150 2275);
DISPLAY INVISIBLE (-7150 2275);
FORCEPROP 1 LAST $LOCATION C160
J 0
(-7100 2375);
DISPLAY 0.978723 (-7100 2375);
FORCEPROP 1 LASTPIN (-7150 2375) $PN 1
J 0
(-7140 2355);
DISPLAY 0.787234 (-7140 2355);
PAINT MONO (-7140 2355);
FORCEPROP 1 LASTPIN (-7150 2175) $PN 2
J 0
(-7140 2155);
DISPLAY 0.787234 (-7140 2155);
PAINT MONO (-7140 2155);
FORCEPROP 0 LAST CDS_LOCATION C160
J 0
(-7100 2425);
DISPLAY 0.680851 (-7100 2425);
DISPLAY INVISIBLE (-7100 2425);
FORCEPROP 0 LAST $SEC 1
J 0
(-7100 2425);
DISPLAY 0.680851 (-7100 2425);
PAINT MONO (-7100 2425);
DISPLAY INVISIBLE (-7100 2425);
FORCEPROP 0 LAST CDS_SEC 1
J 0
(-7100 2425);
DISPLAY 0.680851 (-7100 2425);
DISPLAY INVISIBLE (-7100 2425);
FORCEADD Q_CAP..1
(-7525 4500);
FORCEPROP 1 LAST PART_NUMBER CH4104K1B00
J 0
(-7475 4350);
DISPLAY 0.978723 (-7475 4350);
FORCEPROP 1 LAST MATERIAL X7R
J 0
(-7475 4400);
DISPLAY 0.978723 (-7475 4400);
FORCEPROP 1 LAST TOLERANCE 10%
J 0
(-7475 4450);
DISPLAY 0.978723 (-7475 4450);
FORCEPROP 1 LAST VOLTAGE 25V
J 0
(-7475 4500);
DISPLAY 0.978723 (-7475 4500);
FORCEPROP 1 LAST VALUE 0.1UF
J 0
(-7475 4550);
DISPLAY 0.978723 (-7475 4550);
FORCEPROP 1 LAST PACK_TYPE 0402
J 0
(-7475 4300);
DISPLAY 0.978723 (-7475 4300);
FORCEPROP 1 LAST PATH I90
J 0
(-7475 4650);
DISPLAY 0.978723 (-7475 4650);
PAINT WHITE (-7475 4650);
DISPLAY INVISIBLE (-7475 4650);
FORCEPROP 2 LAST CDS_LIB pure_quanta
J 0
(-7525 4500);
DISPLAY INVISIBLE (-7525 4500);
FORCEPROP 1 LAST $LOCATION C220
J 0
(-7475 4600);
DISPLAY 0.978723 (-7475 4600);
FORCEPROP 1 LASTPIN (-7525 4600) $PN 1
J 0
(-7515 4580);
DISPLAY 0.787234 (-7515 4580);
PAINT MONO (-7515 4580);
FORCEPROP 1 LASTPIN (-7525 4400) $PN 2
J 0
(-7515 4380);
DISPLAY 0.787234 (-7515 4380);
PAINT MONO (-7515 4380);
FORCEPROP 0 LAST CDS_LOCATION C220
J 0
(-7475 4650);
DISPLAY 0.680851 (-7475 4650);
DISPLAY INVISIBLE (-7475 4650);
FORCEPROP 0 LAST $SEC 1
J 0
(-7475 4650);
DISPLAY 0.680851 (-7475 4650);
PAINT MONO (-7475 4650);
DISPLAY INVISIBLE (-7475 4650);
FORCEPROP 0 LAST CDS_SEC 1
J 0
(-7475 4650);
DISPLAY 0.680851 (-7475 4650);
DISPLAY INVISIBLE (-7475 4650);
FORCEADD Q_CAP..1
(-7100 4500);
FORCEPROP 1 LAST MATERIAL X7R
J 0
(-7050 4400);
DISPLAY 0.978723 (-7050 4400);
FORCEPROP 1 LAST PART_NUMBER CH4104K1B00
J 0
(-7050 4350);
DISPLAY 0.978723 (-7050 4350);
FORCEPROP 1 LAST VALUE 0.1UF
J 0
(-7050 4550);
DISPLAY 0.978723 (-7050 4550);
FORCEPROP 1 LAST TOLERANCE 10%
J 0
(-7050 4450);
DISPLAY 0.978723 (-7050 4450);
FORCEPROP 1 LAST PACK_TYPE 0402
J 0
(-7050 4300);
DISPLAY 0.978723 (-7050 4300);
FORCEPROP 1 LAST VOLTAGE 25V
J 0
(-7050 4500);
DISPLAY 0.978723 (-7050 4500);
FORCEPROP 1 LAST PATH I91
J 0
(-7050 4650);
DISPLAY 0.978723 (-7050 4650);
PAINT WHITE (-7050 4650);
DISPLAY INVISIBLE (-7050 4650);
FORCEPROP 2 LAST CDS_LIB pure_quanta
J 0
(-7100 4500);
DISPLAY INVISIBLE (-7100 4500);
FORCEPROP 1 LAST $LOCATION C162
J 0
(-7050 4600);
DISPLAY 0.978723 (-7050 4600);
FORCEPROP 1 LASTPIN (-7100 4600) $PN 1
J 0
(-7090 4580);
DISPLAY 0.787234 (-7090 4580);
PAINT MONO (-7090 4580);
FORCEPROP 1 LASTPIN (-7100 4400) $PN 2
J 0
(-7090 4380);
DISPLAY 0.787234 (-7090 4380);
PAINT MONO (-7090 4380);
FORCEPROP 0 LAST CDS_LOCATION C162
J 0
(-7050 4650);
DISPLAY 0.680851 (-7050 4650);
DISPLAY INVISIBLE (-7050 4650);
FORCEPROP 0 LAST $SEC 1
J 0
(-7050 4650);
DISPLAY 0.680851 (-7050 4650);
PAINT MONO (-7050 4650);
DISPLAY INVISIBLE (-7050 4650);
FORCEPROP 0 LAST CDS_SEC 1
J 0
(-7050 4650);
DISPLAY 0.680851 (-7050 4650);
DISPLAY INVISIBLE (-7050 4650);
FORCEADD Q_CAP..1
(-4725 4725);
FORCEPROP 1 LAST PACK_TYPE C0402
J 0
(-4675 4525);
DISPLAY 0.978723 (-4675 4525);
FORCEPROP 1 LAST PART_NUMBER CH5104KEB02
J 0
(-4675 4575);
DISPLAY 0.978723 (-4675 4575);
FORCEPROP 1 LAST TOLERANCE 10%
J 0
(-4675 4675);
DISPLAY 0.978723 (-4675 4675);
FORCEPROP 1 LAST VALUE 1UF
J 0
(-4675 4775);
DISPLAY 0.978723 (-4675 4775);
FORCEPROP 1 LAST VOLTAGE 25V
J 0
(-4675 4725);
DISPLAY 0.978723 (-4675 4725);
FORCEPROP 1 LAST MATERIAL X6S
J 0
(-4675 4625);
DISPLAY 0.978723 (-4675 4625);
FORCEPROP 1 LAST PATH I92
J 0
(-4675 4875);
DISPLAY 0.978723 (-4675 4875);
PAINT WHITE (-4675 4875);
DISPLAY INVISIBLE (-4675 4875);
FORCEPROP 2 LAST CDS_LIB pure_quanta
J 0
(-4725 4725);
DISPLAY INVISIBLE (-4725 4725);
FORCEPROP 1 LAST $LOCATION C164
J 0
(-4675 4825);
DISPLAY 0.978723 (-4675 4825);
FORCEPROP 1 LASTPIN (-4725 4825) $PN 1
J 0
(-4715 4805);
DISPLAY 0.787234 (-4715 4805);
PAINT MONO (-4715 4805);
FORCEPROP 1 LASTPIN (-4725 4625) $PN 2
J 0
(-4715 4605);
DISPLAY 0.787234 (-4715 4605);
PAINT MONO (-4715 4605);
FORCEPROP 0 LAST CDS_LOCATION C164
J 0
(-4675 4875);
DISPLAY 0.680851 (-4675 4875);
DISPLAY INVISIBLE (-4675 4875);
FORCEPROP 0 LAST $SEC 1
J 0
(-4675 4875);
DISPLAY 0.680851 (-4675 4875);
PAINT MONO (-4675 4875);
DISPLAY INVISIBLE (-4675 4875);
FORCEPROP 0 LAST CDS_SEC 1
J 0
(-4675 4875);
DISPLAY 0.680851 (-4675 4875);
DISPLAY INVISIBLE (-4675 4875);
FORCEADD Q_CAP..1
(-4725 3625);
FORCEPROP 1 LAST PART_NUMBER CH5104KEB02
J 0
(-4675 3475);
DISPLAY 0.978723 (-4675 3475);
FORCEPROP 1 LAST PACK_TYPE C0402
J 0
(-4675 3425);
DISPLAY 0.978723 (-4675 3425);
FORCEPROP 1 LAST TOLERANCE 10%
J 0
(-4675 3575);
DISPLAY 0.978723 (-4675 3575);
FORCEPROP 1 LAST MATERIAL X6S
J 0
(-4675 3525);
DISPLAY 0.978723 (-4675 3525);
FORCEPROP 1 LAST VALUE 1UF
J 0
(-4675 3675);
DISPLAY 0.978723 (-4675 3675);
FORCEPROP 1 LAST VOLTAGE 25V
J 0
(-4675 3625);
DISPLAY 0.978723 (-4675 3625);
FORCEPROP 1 LAST PATH I93
J 0
(-4675 3775);
DISPLAY 0.978723 (-4675 3775);
PAINT WHITE (-4675 3775);
DISPLAY INVISIBLE (-4675 3775);
FORCEPROP 2 LAST CDS_LIB pure_quanta
J 0
(-4725 3625);
DISPLAY INVISIBLE (-4725 3625);
FORCEPROP 1 LAST $LOCATION C165
J 0
(-4675 3725);
DISPLAY 0.978723 (-4675 3725);
FORCEPROP 1 LASTPIN (-4725 3725) $PN 1
J 0
(-4715 3705);
DISPLAY 0.787234 (-4715 3705);
PAINT MONO (-4715 3705);
FORCEPROP 1 LASTPIN (-4725 3525) $PN 2
J 0
(-4715 3505);
DISPLAY 0.787234 (-4715 3505);
PAINT MONO (-4715 3505);
FORCEPROP 0 LAST CDS_LOCATION C165
J 0
(-4675 3775);
DISPLAY 0.680851 (-4675 3775);
DISPLAY INVISIBLE (-4675 3775);
FORCEPROP 0 LAST $SEC 1
J 0
(-4675 3775);
DISPLAY 0.680851 (-4675 3775);
PAINT MONO (-4675 3775);
DISPLAY INVISIBLE (-4675 3775);
FORCEPROP 0 LAST CDS_SEC 1
J 0
(-4675 3775);
DISPLAY 0.680851 (-4675 3775);
DISPLAY INVISIBLE (-4675 3775);
FORCEADD Q_CAP..1
(-7850 3275);
FORCEPROP 1 LAST PART_NUMBER CH5104KEB02
J 0
(-7800 3125);
DISPLAY 0.978723 (-7800 3125);
FORCEPROP 1 LAST PACK_TYPE C0402
J 0
(-7800 3075);
DISPLAY 0.978723 (-7800 3075);
FORCEPROP 1 LAST MATERIAL X6S
J 0
(-7800 3175);
DISPLAY 0.978723 (-7800 3175);
FORCEPROP 1 LAST TOLERANCE 10%
J 0
(-7800 3225);
DISPLAY 0.978723 (-7800 3225);
FORCEPROP 1 LAST VOLTAGE 25V
J 0
(-7800 3275);
DISPLAY 0.978723 (-7800 3275);
FORCEPROP 1 LAST VALUE 1UF
J 0
(-7800 3325);
DISPLAY 0.978723 (-7800 3325);
FORCEPROP 1 LAST PATH I94
J 0
(-7800 3425);
DISPLAY 0.978723 (-7800 3425);
PAINT WHITE (-7800 3425);
DISPLAY INVISIBLE (-7800 3425);
FORCEPROP 2 LAST CDS_LIB pure_quanta
J 0
(-7850 3275);
DISPLAY INVISIBLE (-7850 3275);
FORCEPROP 1 LAST $LOCATION C216
J 0
(-7800 3375);
DISPLAY 0.978723 (-7800 3375);
FORCEPROP 1 LASTPIN (-7850 3375) $PN 1
J 0
(-7840 3355);
DISPLAY 0.787234 (-7840 3355);
PAINT MONO (-7840 3355);
FORCEPROP 1 LASTPIN (-7850 3175) $PN 2
J 0
(-7840 3155);
DISPLAY 0.787234 (-7840 3155);
PAINT MONO (-7840 3155);
FORCEPROP 0 LAST CDS_LOCATION C216
J 0
(-7800 3425);
DISPLAY 0.680851 (-7800 3425);
DISPLAY INVISIBLE (-7800 3425);
FORCEPROP 0 LAST $SEC 1
J 0
(-7800 3425);
DISPLAY 0.680851 (-7800 3425);
PAINT MONO (-7800 3425);
DISPLAY INVISIBLE (-7800 3425);
FORCEPROP 0 LAST CDS_SEC 1
J 0
(-7800 3425);
DISPLAY 0.680851 (-7800 3425);
DISPLAY INVISIBLE (-7800 3425);
FORCEADD Q_CAP..1
(-7800 2300);
FORCEPROP 1 LAST VALUE 1UF
J 0
(-7750 2350);
DISPLAY 0.978723 (-7750 2350);
FORCEPROP 1 LAST VOLTAGE 25V
J 0
(-7750 2300);
DISPLAY 0.978723 (-7750 2300);
FORCEPROP 1 LAST TOLERANCE 10%
J 0
(-7750 2250);
DISPLAY 0.978723 (-7750 2250);
FORCEPROP 1 LAST MATERIAL X6S
J 0
(-7750 2200);
DISPLAY 0.978723 (-7750 2200);
FORCEPROP 1 LAST PART_NUMBER CH5104KEB02
J 0
(-7750 2150);
DISPLAY 0.978723 (-7750 2150);
FORCEPROP 1 LAST PACK_TYPE C0402
J 0
(-7750 2100);
DISPLAY 0.978723 (-7750 2100);
FORCEPROP 1 LAST PATH I95
J 0
(-7750 2450);
DISPLAY 0.978723 (-7750 2450);
PAINT WHITE (-7750 2450);
DISPLAY INVISIBLE (-7750 2450);
FORCEPROP 2 LAST CDS_LIB pure_quanta
J 0
(-7800 2300);
DISPLAY INVISIBLE (-7800 2300);
FORCEPROP 1 LAST $LOCATION C218
J 0
(-7750 2400);
DISPLAY 0.978723 (-7750 2400);
FORCEPROP 1 LASTPIN (-7800 2400) $PN 1
J 0
(-7790 2380);
DISPLAY 0.787234 (-7790 2380);
PAINT MONO (-7790 2380);
FORCEPROP 1 LASTPIN (-7800 2200) $PN 2
J 0
(-7790 2180);
DISPLAY 0.787234 (-7790 2180);
PAINT MONO (-7790 2180);
FORCEPROP 0 LAST CDS_LOCATION C218
J 0
(-7750 2450);
DISPLAY 0.680851 (-7750 2450);
DISPLAY INVISIBLE (-7750 2450);
FORCEPROP 0 LAST $SEC 1
J 0
(-7750 2450);
DISPLAY 0.680851 (-7750 2450);
PAINT MONO (-7750 2450);
DISPLAY INVISIBLE (-7750 2450);
FORCEPROP 0 LAST CDS_SEC 1
J 0
(-7750 2450);
DISPLAY 0.680851 (-7750 2450);
DISPLAY INVISIBLE (-7750 2450);
FORCEADD Q_CAP..1
(-8175 4525);
FORCEPROP 1 LAST VOLTAGE 25V
J 0
(-8125 4525);
DISPLAY 0.978723 (-8125 4525);
FORCEPROP 1 LAST TOLERANCE 10%
J 0
(-8125 4475);
DISPLAY 0.978723 (-8125 4475);
FORCEPROP 1 LAST PACK_TYPE C0402
J 0
(-8125 4325);
DISPLAY 0.978723 (-8125 4325);
FORCEPROP 1 LAST MATERIAL X6S
J 0
(-8125 4425);
DISPLAY 0.978723 (-8125 4425);
FORCEPROP 1 LAST VALUE 1UF
J 0
(-8125 4575);
DISPLAY 0.978723 (-8125 4575);
FORCEPROP 1 LAST PART_NUMBER CH5104KEB02
J 0
(-8125 4375);
DISPLAY 0.978723 (-8125 4375);
FORCEPROP 1 LAST PATH I96
J 0
(-8125 4675);
DISPLAY 0.978723 (-8125 4675);
PAINT WHITE (-8125 4675);
DISPLAY INVISIBLE (-8125 4675);
FORCEPROP 2 LAST CDS_LIB pure_quanta
J 0
(-8175 4525);
DISPLAY INVISIBLE (-8175 4525);
FORCEPROP 1 LAST $LOCATION C195
J 0
(-8125 4625);
DISPLAY 0.978723 (-8125 4625);
FORCEPROP 1 LASTPIN (-8175 4625) $PN 1
J 0
(-8165 4605);
DISPLAY 0.787234 (-8165 4605);
PAINT MONO (-8165 4605);
FORCEPROP 1 LASTPIN (-8175 4425) $PN 2
J 0
(-8165 4405);
DISPLAY 0.787234 (-8165 4405);
PAINT MONO (-8165 4405);
FORCEPROP 0 LAST CDS_LOCATION C195
J 0
(-8125 4675);
DISPLAY 0.680851 (-8125 4675);
DISPLAY INVISIBLE (-8125 4675);
FORCEPROP 0 LAST $SEC 1
J 0
(-8125 4675);
DISPLAY 0.680851 (-8125 4675);
PAINT MONO (-8125 4675);
DISPLAY INVISIBLE (-8125 4675);
FORCEPROP 0 LAST CDS_SEC 1
J 0
(-8125 4675);
DISPLAY 0.680851 (-8125 4675);
DISPLAY INVISIBLE (-8125 4675);
FORCEADD UNIVERSAL_POWER..1
(-8800 6375);
FORCEPROP 3 LASTPIN (-8800 6325) SIG_NAME P3V3_AUX\g
J 0
(-8790 6335);
DISPLAY 0.659574 (-8790 6335);
PAINT MONO (-8790 6335);
DISPLAY INVISIBLE (-8790 6335);
FORCEPROP 1 LAST HDL_POWER P3V3_AUX
J 1
(-8800 6425);
DISPLAY 0.702128 (-8800 6425);
PAINT GREEN (-8800 6425);
FORCEPROP 2 LAST CDS_LIB logical_power
J 0
(-8800 6375);
DISPLAY INVISIBLE (-8800 6375);
FORCEPROP 1 LAST PATH I97
J 0
(-8750 6400);
DISPLAY 0.872340 (-8750 6400);
PAINT AQUA (-8750 6400);
DISPLAY INVISIBLE (-8750 6400);
FORCEADD UNIVERSAL_GND..1
(-8800 5450);
FORCEPROP 3 LASTPIN (-8800 5500) SIG_NAME GND\g
J 0
(-8790 5510);
DISPLAY 0.659574 (-8790 5510);
PAINT MONO (-8790 5510);
DISPLAY INVISIBLE (-8790 5510);
FORCEPROP 2 LAST CDS_LIB logical_power
J 0
(-8800 5450);
PAINT MONO (-8800 5450);
DISPLAY INVISIBLE (-8800 5450);
FORCEPROP 2 LAST ROOM IO_SLOT
J 1
(-9025 5525);
DISPLAY 0.744681 (-9025 5525);
DISPLAY INVISIBLE (-9025 5525);
FORCEPROP 1 LAST HDL_POWER GND
J 1
(-8775 5375);
DISPLAY 0.702128 (-8775 5375);
PAINT GREEN (-8775 5375);
DISPLAY INVISIBLE (-8775 5375);
FORCEPROP 1 LAST PATH I98
J 0
(-8725 5450);
DISPLAY 0.872340 (-8725 5450);
PAINT AQUA (-8725 5450);
DISPLAY INVISIBLE (-8725 5450);
FORCEADD Q_CAP..1
(-8800 5800);
FORCEPROP 1 LAST PACK_TYPE C0402
J 0
(-8750 5600);
DISPLAY 0.978723 (-8750 5600);
FORCEPROP 1 LAST MATERIAL X6S
J 0
(-8750 5700);
DISPLAY 0.978723 (-8750 5700);
FORCEPROP 1 LAST TOLERANCE 10%
J 0
(-8750 5750);
DISPLAY 0.978723 (-8750 5750);
FORCEPROP 1 LAST PART_NUMBER CH5104KEB02
J 0
(-8750 5650);
DISPLAY 0.978723 (-8750 5650);
FORCEPROP 1 LAST VOLTAGE 25V
J 0
(-8750 5800);
DISPLAY 0.978723 (-8750 5800);
FORCEPROP 1 LAST VALUE 1UF
J 0
(-8750 5850);
DISPLAY 0.978723 (-8750 5850);
FORCEPROP 2 LAST CDS_LIB pure_quanta
J 0
(-8800 5800);
DISPLAY INVISIBLE (-8800 5800);
FORCEPROP 2 LAST SEC_TYPE C0402
J 0
(-8750 6000);
DISPLAY 0.680851 (-8750 6000);
DISPLAY INVISIBLE (-8750 6000);
FORCEPROP 1 LAST PATH I99
J 0
(-8750 5950);
DISPLAY 0.978723 (-8750 5950);
PAINT WHITE (-8750 5950);
DISPLAY INVISIBLE (-8750 5950);
FORCEPROP 1 LAST $LOCATION C145
J 0
(-8750 5900);
DISPLAY 0.978723 (-8750 5900);
FORCEPROP 1 LASTPIN (-8800 5900) $PN 1
J 0
(-8790 5880);
DISPLAY 0.787234 (-8790 5880);
PAINT MONO (-8790 5880);
FORCEPROP 1 LASTPIN (-8800 5700) $PN 2
J 0
(-8790 5680);
DISPLAY 0.787234 (-8790 5680);
PAINT MONO (-8790 5680);
FORCEPROP 0 LAST CDS_LOCATION C145
J 0
(-8750 5950);
DISPLAY 0.680851 (-8750 5950);
DISPLAY INVISIBLE (-8750 5950);
FORCEPROP 2 LAST SEC 1
J 0
(-8750 6000);
DISPLAY 0.680851 (-8750 6000);
PAINT MONO (-8750 6000);
DISPLAY INVISIBLE (-8750 6000);
FORCEADD QUANTA_TITLE_BLOCK_C..1
(0 0);
FORCEPROP 0 LAST CDS_CON_LAST_MODIFIED Fri Aug 25 17:25:45 2023
J 0
(-1885 15);
DISPLAY INVISIBLE (-1885 15);
FORCEPROP 2 LAST Q_DEPT 
J 1
(-3763 49);
DISPLAY 1.957447 (-3763 49);
PAINT GREEN (-3763 49);
FORCEPROP 1 LAST CUSTOM_TXT_CDS <CON_LAST_MODIFIED>
J 0
(-1885 15);
DISPLAY 0.978723 (-1885 15);
FORCEPROP 2 LAST CUSTOM_TXT_CDS <XR_PAGE_TITLE>
J 0
(-7890 5250);
DISPLAY 0.638298 (-7890 5250);
PAINT PINK (-7890 5250);
DISPLAY INVISIBLE (-7890 5250);
FORCEPROP 1 LAST CUSTOM_TXT_CDS <NAME_2>
J 0
(-3175 50);
FORCEPROP 1 LAST CUSTOM_TXT_CDS <NAME_1>
J 0
(-3175 175);
FORCEPROP 1 LAST CUSTOM_TXT_CDS <Q_NUMBER>
J 0
(-1403 103);
DISPLAY 1.212766 (-1403 103);
FORCEPROP 1 LAST CUSTOM_TXT_CDS <Q_PROJ>
J 0
(-2382 102);
DISPLAY 1.212766 (-2382 102);
FORCEPROP 1 LAST CUSTOM_TXT_CDS <Q_REV>
J 0
(-184 103);
DISPLAY 1.212766 (-184 103);
FORCEPROP 1 LAST CUSTOM_TXT_CDS <CON_PAGE_NUM> OF <CON_TOTAL_PAGES>
J 0
(-446 18);
DISPLAY 0.978723 (-446 18);
FORCEPROP 1 LAST Q_TITLE FPGA 8/8
J 0
(-9366 26);
DISPLAY 2.446809 (-9366 26);
PAINT GREEN (-9366 26);
FORCEPROP 2 LAST CDS_XR_PAGE_TITLE CR-41 : @SCM_LIB.SCM(SCH_1):PAGE41
J 0
(-7890 5250);
DISPLAY 0.638298 (-7890 5250);
PAINT PINK (-7890 5250);
DISPLAY INVISIBLE (-7890 5250);
FORCEPROP 1 LAST CDS_LMAN_SYM_OUTLINE -9475,6775,100,-125
J 0
(0 0);
DISPLAY 0.468085 (0 0);
PAINT GREEN (0 0);
DISPLAY INVISIBLE (0 0);
FORCEPROP 1 LAST COMMENT_BODY TRUE
J 0
(12 -13);
DISPLAY 0.978723 (12 -13);
PAINT GREEN (12 -13);
DISPLAY INVISIBLE (12 -13);
FORCEPROP 2 LAST CDS_LIB pure_quanta
J 0
(0 0);
DISPLAY INVISIBLE (0 0);
FORCEPROP 2 LAST PAGE_BORDER TRUE
J 0
(-7890 5250);
DISPLAY 0.638298 (-7890 5250);
PAINT PINK (-7890 5250);
DISPLAY INVISIBLE (-7890 5250);
FORCEADD DNS..2
(-1575 5850);
PAINT RED (-1575 5850);
FORCEPROP 1 LAST COMMENT_BODY TRUE
R 1
J 0
(-1500 5625);
DISPLAY 0.872340 (-1500 5625);
PAINT PEACH (-1500 5625);
DISPLAY INVISIBLE (-1500 5625);
FORCEPROP 2 LAST CDS_LIB mstr_misc
J 0
(-1575 5850);
DISPLAY INVISIBLE (-1575 5850);
FORCEADD DNS..2
(-1625 4675);
PAINT RED (-1625 4675);
FORCEPROP 1 LAST COMMENT_BODY TRUE
R 1
J 0
(-1550 4450);
DISPLAY 0.872340 (-1550 4450);
PAINT PEACH (-1550 4450);
DISPLAY INVISIBLE (-1550 4450);
FORCEPROP 2 LAST CDS_LIB mstr_misc
J 0
(-1625 4675);
DISPLAY INVISIBLE (-1625 4675);
FORCEADD DNS..2
(-1575 3600);
PAINT RED (-1575 3600);
FORCEPROP 1 LAST COMMENT_BODY TRUE
R 1
J 0
(-1500 3375);
DISPLAY 0.872340 (-1500 3375);
PAINT PEACH (-1500 3375);
DISPLAY INVISIBLE (-1500 3375);
FORCEPROP 2 LAST CDS_LIB mstr_misc
J 0
(-1575 3600);
DISPLAY INVISIBLE (-1575 3600);
FORCEADD DNS..2
(-575 1925);
PAINT RED (-575 1925);
FORCEPROP 2 LAST CDS_LIB mstr_misc
J 0
(-575 1925);
DISPLAY INVISIBLE (-575 1925);
FORCEPROP 1 LAST COMMENT_BODY TRUE
R 1
J 0
(-500 1700);
DISPLAY 0.872340 (-500 1700);
PAINT PEACH (-500 1700);
DISPLAY INVISIBLE (-500 1700);
WIRE 16 -1 (-750 3875)(-750 3825);
WIRE 16 -1 (-250 2200)(-250 2175);
WIRE 16 -1 (-6725 4775)(-6725 4725);
WIRE 16 -1 (-5575 4075)(-5575 3825);
WIRE 16 -1 (-6825 3525)(-6825 3475);
WIRE 16 -1 (-425 4975)(-425 4925);
WIRE 16 -1 (-575 6125)(-575 6075);
WIRE 16 -1 (-8775 4975)(-8775 4725);
WIRE 16 -1 (-5575 5175)(-5575 4925);
WIRE 16 -1 (-8725 3750)(-8725 3475);
WIRE 16 -1 (-6775 2550)(-6775 2500);
WIRE 16 -1 (-8800 6325)(-8800 6025);
WIRE 16 -1 (-5575 6375)(-5575 6075);
WIRE 16 -1 (-6025 2450)(-6025 2175);
WIRE 16 -1 (-8800 5700)(-8800 5500);
WIRE 16 -1 (-7900 5600)(-7900 5475);
WIRE 16 -1 (-2600 1575)(-2600 1700);
WIRE 16 -1 (-7150 1900)(-7150 2025);
WIRE 16 -1 (-7200 2875)(-7200 3000);
WIRE 16 -1 (-7100 4125)(-7100 4250);
WIRE 16 -1 (-2625 3225)(-2625 3350);
WIRE 16 -1 (-2625 4325)(-2625 4450);
WIRE 16 -1 (-2600 5475)(-2600 5600);
WIRE 16 -1 (-1550 5950)(-1550 6075);
WIRE 16 -1 (-575 6075)(-1550 6075);
WIRE 16 -1 (-2250 5950)(-2250 6075);
WIRE 16 -1 (-1550 6075)(-2250 6075);
WIRE 16 -1 (-2825 5950)(-2825 6075);
WIRE 16 -1 (-2825 6075)(-2250 6075);
WIRE 16 -1 (-3400 5950)(-3400 6075);
WIRE 16 -1 (-3400 6075)(-2825 6075);
WIRE 16 -1 (-4700 6075)(-5000 6075);
WIRE 16 -1 (-4700 5975)(-4700 6075);
WIRE 16 -1 (-4025 5950)(-4025 6075);
WIRE 16 -1 (-3400 6075)(-4025 6075);
WIRE 16 -1 (-4025 6075)(-4700 6075);
WIRE 16 -1 (-1550 5750)(-1550 5600);
WIRE 16 -1 (-2250 5600)(-2250 5750);
WIRE 16 -1 (-2250 5600)(-1550 5600);
WIRE 16 -1 (-2600 5600)(-2250 5600);
WIRE 16 -1 (-2600 5600)(-2825 5600);
WIRE 16 -1 (-2825 5600)(-2825 5750);
WIRE 16 -1 (-3400 5600)(-3400 5750);
WIRE 16 -1 (-3400 5600)(-2825 5600);
WIRE 16 -1 (-4025 5600)(-4025 5750);
WIRE 16 -1 (-3400 5600)(-4025 5600);
WIRE 16 -1 (-4700 5600)(-4025 5600);
WIRE 16 -1 (-4700 5775)(-4700 5600);
WIRE 16 -1 (-1575 4775)(-1575 4925);
WIRE 16 -1 (-425 4925)(-1575 4925);
WIRE 16 -1 (-2300 4800)(-2300 4925);
WIRE 16 -1 (-1575 4925)(-2300 4925);
WIRE 16 -1 (-2875 4800)(-2875 4925);
WIRE 16 -1 (-2875 4925)(-2300 4925);
WIRE 16 -1 (-3450 4800)(-3450 4925);
WIRE 16 -1 (-2875 4925)(-3450 4925);
WIRE 16 -1 (-4725 4925)(-5025 4925);
WIRE 16 -1 (-4725 4825)(-4725 4925);
WIRE 16 -1 (-4050 4800)(-4050 4925);
WIRE 16 -1 (-3450 4925)(-4050 4925);
WIRE 16 -1 (-4050 4925)(-4725 4925);
WIRE 16 -1 (-1575 4575)(-1575 4450);
WIRE 16 -1 (-2300 4450)(-2300 4600);
WIRE 16 -1 (-2300 4450)(-1575 4450);
WIRE 16 -1 (-2625 4450)(-2300 4450);
WIRE 16 -1 (-2875 4450)(-2875 4600);
WIRE 16 -1 (-2625 4450)(-2875 4450);
WIRE 16 -1 (-3450 4450)(-3450 4600);
WIRE 16 -1 (-2875 4450)(-3450 4450);
WIRE 16 -1 (-4050 4450)(-4050 4600);
WIRE 16 -1 (-3450 4450)(-4050 4450);
WIRE 16 -1 (-4725 4450)(-4050 4450);
WIRE 16 -1 (-4725 4625)(-4725 4450);
WIRE 16 -1 (-575 2050)(-575 2175);
WIRE 16 -1 (-250 2175)(-575 2175);
WIRE 16 -1 (-1200 2050)(-1200 2175);
WIRE 16 -1 (-1200 2175)(-575 2175);
WIRE 16 -1 (-1775 2050)(-1775 2175);
WIRE 16 -1 (-1775 2175)(-1200 2175);
WIRE 16 -1 (-2325 2050)(-2325 2175);
WIRE 16 -1 (-2325 2175)(-1775 2175);
WIRE 16 -1 (-2875 2050)(-2875 2175);
WIRE 16 -1 (-2875 2175)(-2325 2175);
WIRE 16 -1 (-3450 2050)(-3450 2175);
WIRE 16 -1 (-2875 2175)(-3450 2175);
WIRE 16 -1 (-4075 2050)(-4075 2175);
WIRE 16 -1 (-3450 2175)(-4075 2175);
WIRE 16 -1 (-4650 2075)(-4650 2175);
WIRE 16 -1 (-4075 2175)(-4650 2175);
WIRE 16 -1 (-5225 2050)(-5225 2175);
WIRE 16 -1 (-4650 2175)(-5225 2175);
WIRE 16 -1 (-5450 2175)(-5225 2175);
WIRE 16 -1 (-5225 1850)(-5225 1700);
WIRE 16 -1 (-5225 1700)(-4650 1700);
WIRE 16 -1 (-4650 1875)(-4650 1700);
WIRE 16 -1 (-4075 1700)(-4650 1700);
WIRE 16 -1 (-4075 1700)(-4075 1850);
WIRE 16 -1 (-3450 1700)(-4075 1700);
WIRE 16 -1 (-3450 1700)(-3450 1850);
WIRE 16 -1 (-2875 1700)(-3450 1700);
WIRE 16 -1 (-2875 1700)(-2875 1850);
WIRE 16 -1 (-2600 1700)(-2875 1700);
WIRE 16 -1 (-2600 1700)(-2325 1700);
WIRE 16 -1 (-2325 1700)(-2325 1850);
WIRE 16 -1 (-2325 1700)(-1775 1700);
WIRE 16 -1 (-1775 1700)(-1775 1850);
WIRE 16 -1 (-1775 1700)(-1200 1700);
WIRE 16 -1 (-1200 1700)(-1200 1850);
WIRE 16 -1 (-1200 1700)(-575 1700);
WIRE 16 -1 (-575 1850)(-575 1700);
WIRE 16 -1 (-7800 2500)(-8100 2500);
WIRE 16 -1 (-7800 2400)(-7800 2500);
WIRE 16 -1 (-7150 2375)(-7150 2500);
WIRE 16 -1 (-6775 2500)(-7150 2500);
WIRE 16 -1 (-7150 2500)(-7800 2500);
WIRE 16 -1 (-7200 3000)(-7200 3150);
WIRE 16 -1 (-7200 3000)(-7850 3000);
WIRE 16 -1 (-7850 3175)(-7850 3000);
WIRE 16 -1 (-7850 3475)(-8150 3475);
WIRE 16 -1 (-7850 3375)(-7850 3475);
WIRE 16 -1 (-7200 3350)(-7200 3475);
WIRE 16 -1 (-6825 3475)(-7200 3475);
WIRE 16 -1 (-7200 3475)(-7850 3475);
WIRE 16 -1 (-8175 4425)(-8175 4250);
WIRE 16 -1 (-8175 4250)(-7525 4250);
WIRE 16 -1 (-7525 4250)(-7525 4400);
WIRE 16 -1 (-7100 4250)(-7525 4250);
WIRE 16 -1 (-7100 4250)(-7100 4400);
WIRE 16 -1 (-8175 4725)(-8475 4725);
WIRE 16 -1 (-8175 4625)(-8175 4725);
WIRE 16 -1 (-8175 4725)(-7525 4725);
WIRE 16 -1 (-7525 4600)(-7525 4725);
WIRE 16 -1 (-7100 4725)(-7525 4725);
WIRE 16 -1 (-7100 4600)(-7100 4725);
WIRE 16 -1 (-6725 4725)(-7100 4725);
WIRE 16 -1 (-8800 5900)(-8800 6025);
WIRE 16 -1 (-7900 6025)(-8800 6025);
WIRE 16 -1 (-7900 5800)(-7900 6025);
WIRE 16 -1 (-4725 3825)(-5025 3825);
WIRE 16 -1 (-4725 3725)(-4725 3825);
WIRE 16 -1 (-4050 3700)(-4050 3825);
WIRE 16 -1 (-4050 3825)(-4725 3825);
WIRE 16 -1 (-3425 3700)(-3425 3825);
WIRE 16 -1 (-3425 3825)(-4050 3825);
WIRE 16 -1 (-3425 3825)(-2850 3825);
WIRE 16 -1 (-2850 3700)(-2850 3825);
WIRE 16 -1 (-2850 3825)(-2275 3825);
WIRE 16 -1 (-2275 3700)(-2275 3825);
WIRE 16 -1 (-1550 3825)(-2275 3825);
WIRE 16 -1 (-1550 3675)(-1550 3825);
WIRE 16 -1 (-750 3825)(-1550 3825);
WIRE 16 -1 (-5200 6075)(-5575 6075);
WIRE 16 -1 (-5225 4925)(-5575 4925);
WIRE 16 -1 (-4725 3525)(-4725 3350);
WIRE 16 -1 (-4725 3350)(-4050 3350);
WIRE 16 -1 (-4050 3350)(-4050 3500);
WIRE 16 -1 (-3425 3350)(-4050 3350);
WIRE 16 -1 (-3425 3350)(-3425 3500);
WIRE 16 -1 (-3425 3350)(-2850 3350);
WIRE 16 -1 (-2850 3350)(-2850 3500);
WIRE 16 -1 (-2625 3350)(-2850 3350);
WIRE 16 -1 (-2625 3350)(-2275 3350);
WIRE 16 -1 (-2275 3350)(-2275 3500);
WIRE 16 -1 (-2275 3350)(-1550 3350);
WIRE 16 -1 (-1550 3475)(-1550 3350);
WIRE 16 -1 (-5225 3825)(-5575 3825);
WIRE 16 -1 (-8300 2500)(-8425 2500);
WIRE 16 -1 (-8425 3475)(-8350 3475);
WIRE 16 -1 (-8425 3475)(-8425 2500);
WIRE 16 -1 (-8425 3475)(-8725 3475);
WIRE 16 -1 (-8675 4725)(-8775 4725);
WIRE 16 -1 (-7800 2200)(-7800 2025);
WIRE 16 -1 (-7150 2025)(-7800 2025);
WIRE 16 -1 (-7150 2025)(-7150 2175);
WIRE 16 -1 (-5650 2175)(-6025 2175);
DOT 1 (-2875 4450);
DOT 1 (-1200 2175);
DOT 1 (-7200 3000);
DOT 1 (-8800 6025);
DOT 1 (-7800 2500);
DOT 1 (-4075 1700);
DOT 1 (-4075 2175);
DOT 1 (-4650 1700);
DOT 1 (-4650 2175);
DOT 1 (-5225 2175);
DOT 1 (-3450 1700);
DOT 1 (-3450 2175);
DOT 1 (-2875 1700);
DOT 1 (-2875 2175);
DOT 1 (-2325 1700);
DOT 1 (-2325 2175);
DOT 1 (-1775 1700);
DOT 1 (-1775 2175);
DOT 1 (-1200 1700);
DOT 1 (-575 2175);
DOT 1 (-2600 1700);
DOT 1 (-4050 3350);
DOT 1 (-2850 3350);
DOT 1 (-2850 3825);
DOT 1 (-2275 3350);
DOT 1 (-2275 3825);
DOT 1 (-3450 4450);
DOT 1 (-3450 4925);
DOT 1 (-2875 4925);
DOT 1 (-2300 4450);
DOT 1 (-2300 4925);
DOT 1 (-2825 5600);
DOT 1 (-2825 6075);
DOT 1 (-2250 5600);
DOT 1 (-2250 6075);
DOT 1 (-2600 5600);
DOT 1 (-7525 4725);
DOT 1 (-7525 4250);
DOT 1 (-1550 3825);
DOT 1 (-1575 4925);
DOT 1 (-1550 6075);
DOT 1 (-3400 6075);
DOT 1 (-7200 3475);
DOT 1 (-7150 2500);
DOT 1 (-7150 2025);
DOT 1 (-8425 3475);
DOT 1 (-7850 3475);
DOT 1 (-7100 4250);
DOT 1 (-8175 4725);
DOT 1 (-7100 4725);
DOT 1 (-4050 3825);
DOT 1 (-3425 3825);
DOT 1 (-4725 3825);
DOT 1 (-2625 3350);
DOT 1 (-4725 4925);
DOT 1 (-4050 4450);
DOT 1 (-4050 4925);
DOT 1 (-4700 6075);
DOT 1 (-4025 5600);
DOT 1 (-4025 6075);
DOT 1 (-3400 5600);
DOT 1 (-2625 4450);
DOT 1 (-3425 3350);
FORCENOTE
120OHM
(-5600 2025) 0;
DISPLAY LEFT (-5600 2025);
DISPLAY 0.638298 (-5600 2025);
PAINT ORANGE (-5600 2025);
QUIT
